FILE_TYPE = MACRO_DRAWING;
SET COLOR_WIRE YELLOW;
SET COLOR_PROP ORANGE;
SET COLOR_DOT WHITE;
SET COLOR_ARC YELLOW;
SET COLOR_BODY GREEN;
SET COLOR_NOTE PURPLE;
SET PROP_DISPLAY VALUE;
SET PAGE_NUMBER P39;
FORCEADD GENOA_SP5..3
(-4750 3675);
FORCEPROP 1 LAST LOCATION U26
J 0
(-5395 6506);
DISPLAY 0.489362 (-5395 6506);
PAINT SKYBLUE (-5395 6506);
FORCEPROP 0 LAST $SEC 3
J 0
(-5375 6550);
DISPLAY 0.680851 (-5375 6550);
PAINT MONO (-5375 6550);
DISPLAY INVISIBLE (-5375 6550);
FORCEPROP 0 LAST CDS_SEC 3
J 0
(-5400 6475);
DISPLAY 1.021277 (-5400 6475);
DISPLAY INVISIBLE (-5400 6475);
FORCEPROP 0 LASTPIN (-5550 3050) $PN BC57
J 2
(-5560 3060);
DISPLAY 0.489362 (-5560 3060);
PAINT MONO (-5560 3060);
FORCEPROP 0 LASTPIN (-5550 3000) $PN BD56
J 2
(-5560 3010);
DISPLAY 0.489362 (-5560 3010);
PAINT MONO (-5560 3010);
FORCEPROP 0 LASTPIN (-5550 1900) $PN BF56
J 2
(-5560 1910);
DISPLAY 0.489362 (-5560 1910);
PAINT MONO (-5560 1910);
FORCEPROP 0 LASTPIN (-5550 1850) $PN BG57
J 2
(-5560 1860);
DISPLAY 0.489362 (-5560 1860);
PAINT MONO (-5560 1860);
FORCEPROP 0 LASTPIN (-5550 2200) $PN AT55
J 2
(-5560 2210);
DISPLAY 0.489362 (-5560 2210);
PAINT MONO (-5560 2210);
FORCEPROP 0 LASTPIN (-5550 2100) $PN AU55
J 2
(-5560 2110);
DISPLAY 0.489362 (-5560 2110);
PAINT MONO (-5560 2110);
FORCEPROP 0 LASTPIN (-5550 2900) $PN AV56
J 2
(-5560 2910);
DISPLAY 0.489362 (-5560 2910);
PAINT MONO (-5560 2910);
FORCEPROP 0 LASTPIN (-5550 2850) $PN AW55
J 2
(-5560 2860);
DISPLAY 0.489362 (-5560 2860);
PAINT MONO (-5560 2860);
FORCEPROP 0 LASTPIN (-5550 2750) $PN BN55
J 2
(-5560 2760);
DISPLAY 0.489362 (-5560 2760);
PAINT MONO (-5560 2760);
FORCEPROP 0 LASTPIN (-5550 1750) $PN AU57
J 2
(-5560 1760);
DISPLAY 0.489362 (-5560 1760);
PAINT MONO (-5560 1760);
FORCEPROP 0 LASTPIN (-5550 1700) $PN AV55
J 2
(-5560 1710);
DISPLAY 0.489362 (-5560 1710);
PAINT MONO (-5560 1710);
FORCEPROP 0 LASTPIN (-5550 1600) $PN BP55
J 2
(-5560 1610);
DISPLAY 0.489362 (-5560 1610);
PAINT MONO (-5560 1610);
FORCEPROP 0 LASTPIN (-5550 3900) $PN AW57
J 2
(-5560 3910);
DISPLAY 0.489362 (-5560 3910);
PAINT MONO (-5560 3910);
FORCEPROP 0 LASTPIN (-5550 3850) $PN AY56
J 2
(-5560 3860);
DISPLAY 0.489362 (-5560 3860);
PAINT MONO (-5560 3860);
FORCEPROP 0 LASTPIN (-5550 3800) $PN AY55
J 2
(-5560 3810);
DISPLAY 0.489362 (-5560 3810);
PAINT MONO (-5560 3810);
FORCEPROP 0 LASTPIN (-5550 3750) $PN BA55
J 2
(-5560 3760);
DISPLAY 0.489362 (-5560 3760);
PAINT MONO (-5560 3760);
FORCEPROP 0 LASTPIN (-5550 3700) $PN BA57
J 2
(-5560 3710);
DISPLAY 0.489362 (-5560 3710);
PAINT MONO (-5560 3710);
FORCEPROP 0 LASTPIN (-5550 3650) $PN BB56
J 2
(-5560 3660);
DISPLAY 0.489362 (-5560 3660);
PAINT MONO (-5560 3660);
FORCEPROP 0 LASTPIN (-5550 3600) $PN BB55
J 2
(-5560 3610);
DISPLAY 0.489362 (-5560 3610);
PAINT MONO (-5560 3610);
FORCEPROP 0 LASTPIN (-3950 2450) $PN AJ57
J 0
(-3940 2460);
DISPLAY 0.489362 (-3940 2460);
PAINT MONO (-3940 2460);
FORCEPROP 0 LASTPIN (-3950 2400) $PN AK55
J 0
(-3940 2410);
DISPLAY 0.489362 (-3940 2410);
PAINT MONO (-3940 2410);
FORCEPROP 0 LASTPIN (-3950 2350) $PN AK56
J 0
(-3940 2360);
DISPLAY 0.489362 (-3940 2360);
PAINT MONO (-3940 2360);
FORCEPROP 0 LASTPIN (-3950 2300) $PN AL55
J 0
(-3940 2310);
DISPLAY 0.489362 (-3940 2310);
PAINT MONO (-3940 2310);
FORCEPROP 0 LASTPIN (-3950 2250) $PN AN57
J 0
(-3940 2260);
DISPLAY 0.489362 (-3940 2260);
PAINT MONO (-3940 2260);
FORCEPROP 0 LASTPIN (-3950 2200) $PN AP55
J 0
(-3940 2210);
DISPLAY 0.489362 (-3940 2210);
PAINT MONO (-3940 2210);
FORCEPROP 0 LASTPIN (-3950 2150) $PN AP56
J 0
(-3940 2160);
DISPLAY 0.489362 (-3940 2160);
PAINT MONO (-3940 2160);
FORCEPROP 0 LASTPIN (-3950 2100) $PN AR55
J 0
(-3940 2110);
DISPLAY 0.489362 (-3940 2110);
PAINT MONO (-3940 2110);
FORCEPROP 0 LASTPIN (-3950 6050) $PN E57
J 0
(-3940 6060);
DISPLAY 0.489362 (-3940 6060);
PAINT MONO (-3940 6060);
FORCEPROP 0 LASTPIN (-3950 6000) $PN F55
J 0
(-3940 6010);
DISPLAY 0.489362 (-3940 6010);
PAINT MONO (-3940 6010);
FORCEPROP 0 LASTPIN (-3950 5950) $PN F56
J 0
(-3940 5960);
DISPLAY 0.489362 (-3940 5960);
PAINT MONO (-3940 5960);
FORCEPROP 0 LASTPIN (-3950 5900) $PN G55
J 0
(-3940 5910);
DISPLAY 0.489362 (-3940 5910);
PAINT MONO (-3940 5910);
FORCEPROP 0 LASTPIN (-3950 5850) $PN J57
J 0
(-3940 5860);
DISPLAY 0.489362 (-3940 5860);
PAINT MONO (-3940 5860);
FORCEPROP 0 LASTPIN (-3950 5800) $PN K55
J 0
(-3940 5810);
DISPLAY 0.489362 (-3940 5810);
PAINT MONO (-3940 5810);
FORCEPROP 0 LASTPIN (-3950 5750) $PN K56
J 0
(-3940 5760);
DISPLAY 0.489362 (-3940 5760);
PAINT MONO (-3940 5760);
FORCEPROP 0 LASTPIN (-3950 5700) $PN L55
J 0
(-3940 5710);
DISPLAY 0.489362 (-3940 5710);
PAINT MONO (-3940 5710);
FORCEPROP 0 LASTPIN (-3950 5600) $PN L57
J 0
(-3940 5610);
DISPLAY 0.489362 (-3940 5610);
PAINT MONO (-3940 5610);
FORCEPROP 0 LASTPIN (-3950 5550) $PN M55
J 0
(-3940 5560);
DISPLAY 0.489362 (-3940 5560);
PAINT MONO (-3940 5560);
FORCEPROP 0 LASTPIN (-3950 5500) $PN M56
J 0
(-3940 5510);
DISPLAY 0.489362 (-3940 5510);
PAINT MONO (-3940 5510);
FORCEPROP 0 LASTPIN (-3950 5450) $PN N55
J 0
(-3940 5460);
DISPLAY 0.489362 (-3940 5460);
PAINT MONO (-3940 5460);
FORCEPROP 0 LASTPIN (-3950 5400) $PN R57
J 0
(-3940 5410);
DISPLAY 0.489362 (-3940 5410);
PAINT MONO (-3940 5410);
FORCEPROP 0 LASTPIN (-3950 5350) $PN T55
J 0
(-3940 5360);
DISPLAY 0.489362 (-3940 5360);
PAINT MONO (-3940 5360);
FORCEPROP 0 LASTPIN (-3950 5300) $PN T56
J 0
(-3940 5310);
DISPLAY 0.489362 (-3940 5310);
PAINT MONO (-3940 5310);
FORCEPROP 0 LASTPIN (-3950 5250) $PN U55
J 0
(-3940 5260);
DISPLAY 0.489362 (-3940 5260);
PAINT MONO (-3940 5260);
FORCEPROP 0 LASTPIN (-3950 5150) $PN U57
J 0
(-3940 5160);
DISPLAY 0.489362 (-3940 5160);
PAINT MONO (-3940 5160);
FORCEPROP 0 LASTPIN (-3950 5100) $PN V55
J 0
(-3940 5110);
DISPLAY 0.489362 (-3940 5110);
PAINT MONO (-3940 5110);
FORCEPROP 0 LASTPIN (-3950 5050) $PN V56
J 0
(-3940 5060);
DISPLAY 0.489362 (-3940 5060);
PAINT MONO (-3940 5060);
FORCEPROP 0 LASTPIN (-3950 5000) $PN W55
J 0
(-3940 5010);
DISPLAY 0.489362 (-3940 5010);
PAINT MONO (-3940 5010);
FORCEPROP 0 LASTPIN (-3950 4950) $PN AA57
J 0
(-3940 4960);
DISPLAY 0.489362 (-3940 4960);
PAINT MONO (-3940 4960);
FORCEPROP 0 LASTPIN (-3950 4900) $PN AB55
J 0
(-3940 4910);
DISPLAY 0.489362 (-3940 4910);
PAINT MONO (-3940 4910);
FORCEPROP 0 LASTPIN (-3950 4850) $PN AB56
J 0
(-3940 4860);
DISPLAY 0.489362 (-3940 4860);
PAINT MONO (-3940 4860);
FORCEPROP 0 LASTPIN (-3950 4800) $PN AC55
J 0
(-3940 4810);
DISPLAY 0.489362 (-3940 4810);
PAINT MONO (-3940 4810);
FORCEPROP 0 LASTPIN (-3950 4700) $PN AC57
J 0
(-3940 4710);
DISPLAY 0.489362 (-3940 4710);
PAINT MONO (-3940 4710);
FORCEPROP 0 LASTPIN (-3950 4650) $PN AD55
J 0
(-3940 4660);
DISPLAY 0.489362 (-3940 4660);
PAINT MONO (-3940 4660);
FORCEPROP 0 LASTPIN (-3950 4600) $PN AD56
J 0
(-3940 4610);
DISPLAY 0.489362 (-3940 4610);
PAINT MONO (-3940 4610);
FORCEPROP 0 LASTPIN (-3950 4550) $PN AE55
J 0
(-3940 4560);
DISPLAY 0.489362 (-3940 4560);
PAINT MONO (-3940 4560);
FORCEPROP 0 LASTPIN (-3950 4500) $PN AG57
J 0
(-3940 4510);
DISPLAY 0.489362 (-3940 4510);
PAINT MONO (-3940 4510);
FORCEPROP 0 LASTPIN (-3950 4450) $PN AH55
J 0
(-3940 4460);
DISPLAY 0.489362 (-3940 4460);
PAINT MONO (-3940 4460);
FORCEPROP 0 LASTPIN (-3950 4400) $PN AH56
J 0
(-3940 4410);
DISPLAY 0.489362 (-3940 4410);
PAINT MONO (-3940 4410);
FORCEPROP 0 LASTPIN (-3950 4350) $PN AJ55
J 0
(-3940 4360);
DISPLAY 0.489362 (-3940 4360);
PAINT MONO (-3940 4360);
FORCEPROP 0 LASTPIN (-5550 6050) $PN G57
J 2
(-5560 6060);
DISPLAY 0.489362 (-5560 6060);
PAINT MONO (-5560 6060);
FORCEPROP 0 LASTPIN (-5550 5950) $PN N57
J 2
(-5560 5960);
DISPLAY 0.489362 (-5560 5960);
PAINT MONO (-5560 5960);
FORCEPROP 0 LASTPIN (-5550 5850) $PN W57
J 2
(-5560 5860);
DISPLAY 0.489362 (-5560 5860);
PAINT MONO (-5560 5860);
FORCEPROP 0 LASTPIN (-5550 5750) $PN AE57
J 2
(-5560 5760);
DISPLAY 0.489362 (-5560 5760);
PAINT MONO (-5560 5760);
FORCEPROP 0 LASTPIN (-5550 5650) $PN AL57
J 2
(-5560 5660);
DISPLAY 0.489362 (-5560 5660);
PAINT MONO (-5560 5660);
FORCEPROP 0 LASTPIN (-5550 5550) $PN J55
J 2
(-5560 5560);
DISPLAY 0.489362 (-5560 5560);
PAINT MONO (-5560 5560);
FORCEPROP 0 LASTPIN (-5550 5450) $PN R55
J 2
(-5560 5460);
DISPLAY 0.489362 (-5560 5460);
PAINT MONO (-5560 5460);
FORCEPROP 0 LASTPIN (-5550 5350) $PN AA55
J 2
(-5560 5360);
DISPLAY 0.489362 (-5560 5360);
PAINT MONO (-5560 5360);
FORCEPROP 0 LASTPIN (-5550 5250) $PN AG55
J 2
(-5560 5260);
DISPLAY 0.489362 (-5560 5260);
PAINT MONO (-5560 5260);
FORCEPROP 0 LASTPIN (-5550 5150) $PN AN55
J 2
(-5560 5160);
DISPLAY 0.489362 (-5560 5160);
PAINT MONO (-5560 5160);
FORCEPROP 0 LASTPIN (-5550 6000) $PN H56
J 2
(-5560 6010);
DISPLAY 0.489362 (-5560 6010);
PAINT MONO (-5560 6010);
FORCEPROP 0 LASTPIN (-5550 5900) $PN P56
J 2
(-5560 5910);
DISPLAY 0.489362 (-5560 5910);
PAINT MONO (-5560 5910);
FORCEPROP 0 LASTPIN (-5550 5800) $PN Y56
J 2
(-5560 5810);
DISPLAY 0.489362 (-5560 5810);
PAINT MONO (-5560 5810);
FORCEPROP 0 LASTPIN (-5550 5700) $PN AF56
J 2
(-5560 5710);
DISPLAY 0.489362 (-5560 5710);
PAINT MONO (-5560 5710);
FORCEPROP 0 LASTPIN (-5550 5600) $PN AM56
J 2
(-5560 5610);
DISPLAY 0.489362 (-5560 5610);
PAINT MONO (-5560 5610);
FORCEPROP 0 LASTPIN (-5550 5500) $PN H55
J 2
(-5560 5510);
DISPLAY 0.489362 (-5560 5510);
PAINT MONO (-5560 5510);
FORCEPROP 0 LASTPIN (-5550 5400) $PN P55
J 2
(-5560 5410);
DISPLAY 0.489362 (-5560 5410);
PAINT MONO (-5560 5410);
FORCEPROP 0 LASTPIN (-5550 5300) $PN Y55
J 2
(-5560 5310);
DISPLAY 0.489362 (-5560 5310);
PAINT MONO (-5560 5310);
FORCEPROP 0 LASTPIN (-5550 5200) $PN AF55
J 2
(-5560 5210);
DISPLAY 0.489362 (-5560 5210);
PAINT MONO (-5560 5210);
FORCEPROP 0 LASTPIN (-5550 5100) $PN AM55
J 2
(-5560 5110);
DISPLAY 0.489362 (-5560 5110);
PAINT MONO (-5560 5110);
FORCEPROP 0 LASTPIN (-5550 2650) $PN BC55
J 2
(-5560 2660);
DISPLAY 0.489362 (-5560 2660);
PAINT MONO (-5560 2660);
FORCEPROP 0 LASTPIN (-5550 2550) $PN BM55
J 2
(-5560 2560);
DISPLAY 0.489362 (-5560 2560);
PAINT MONO (-5560 2560);
FORCEPROP 0 LASTPIN (-5550 2500) $PN BN57
J 2
(-5560 2510);
DISPLAY 0.489362 (-5560 2510);
PAINT MONO (-5560 2510);
FORCEPROP 0 LASTPIN (-5550 2400) $PN BP56
J 2
(-5560 2410);
DISPLAY 0.489362 (-5560 2410);
PAINT MONO (-5560 2410);
FORCEPROP 0 LASTPIN (-5550 1500) $PN BL55
J 2
(-5560 1510);
DISPLAY 0.489362 (-5560 1510);
PAINT MONO (-5560 1510);
FORCEPROP 0 LASTPIN (-5550 1450) $PN BM56
J 2
(-5560 1460);
DISPLAY 0.489362 (-5560 1460);
PAINT MONO (-5560 1460);
FORCEPROP 0 LASTPIN (-5550 1350) $PN BR57
J 2
(-5560 1360);
DISPLAY 0.489362 (-5560 1360);
PAINT MONO (-5560 1360);
FORCEPROP 0 LASTPIN (-5550 3500) $PN BG55
J 2
(-5560 3510);
DISPLAY 0.489362 (-5560 3510);
PAINT MONO (-5560 3510);
FORCEPROP 0 LASTPIN (-5550 3450) $PN BH55
J 2
(-5560 3460);
DISPLAY 0.489362 (-5560 3460);
PAINT MONO (-5560 3460);
FORCEPROP 0 LASTPIN (-5550 3400) $PN BH56
J 2
(-5560 3410);
DISPLAY 0.489362 (-5560 3410);
PAINT MONO (-5560 3410);
FORCEPROP 0 LASTPIN (-5550 3350) $PN BJ57
J 2
(-5560 3360);
DISPLAY 0.489362 (-5560 3360);
PAINT MONO (-5560 3360);
FORCEPROP 0 LASTPIN (-5550 3300) $PN BJ55
J 2
(-5560 3310);
DISPLAY 0.489362 (-5560 3310);
PAINT MONO (-5560 3310);
FORCEPROP 0 LASTPIN (-5550 3250) $PN BK55
J 2
(-5560 3260);
DISPLAY 0.489362 (-5560 3260);
PAINT MONO (-5560 3260);
FORCEPROP 0 LASTPIN (-5550 3200) $PN BK56
J 2
(-5560 3210);
DISPLAY 0.489362 (-5560 3210);
PAINT MONO (-5560 3210);
FORCEPROP 0 LASTPIN (-3950 2000) $PN BY56
J 0
(-3940 2010);
DISPLAY 0.489362 (-3940 2010);
PAINT MONO (-3940 2010);
FORCEPROP 0 LASTPIN (-3950 1950) $PN CA55
J 0
(-3940 1960);
DISPLAY 0.489362 (-3940 1960);
PAINT MONO (-3940 1960);
FORCEPROP 0 LASTPIN (-3950 1900) $PN CA57
J 0
(-3940 1910);
DISPLAY 0.489362 (-3940 1910);
PAINT MONO (-3940 1910);
FORCEPROP 0 LASTPIN (-3950 1850) $PN CB55
J 0
(-3940 1860);
DISPLAY 0.489362 (-3940 1860);
PAINT MONO (-3940 1860);
FORCEPROP 0 LASTPIN (-3950 1800) $PN BT56
J 0
(-3940 1810);
DISPLAY 0.489362 (-3940 1810);
PAINT MONO (-3940 1810);
FORCEPROP 0 LASTPIN (-3950 1750) $PN BU55
J 0
(-3940 1760);
DISPLAY 0.489362 (-3940 1760);
PAINT MONO (-3940 1760);
FORCEPROP 0 LASTPIN (-3950 1700) $PN BU57
J 0
(-3940 1710);
DISPLAY 0.489362 (-3940 1710);
PAINT MONO (-3940 1710);
FORCEPROP 0 LASTPIN (-3950 1650) $PN BV55
J 0
(-3940 1660);
DISPLAY 0.489362 (-3940 1660);
PAINT MONO (-3940 1660);
FORCEPROP 0 LASTPIN (-3950 4250) $PN CB56
J 0
(-3940 4260);
DISPLAY 0.489362 (-3940 4260);
PAINT MONO (-3940 4260);
FORCEPROP 0 LASTPIN (-3950 4200) $PN CC55
J 0
(-3940 4210);
DISPLAY 0.489362 (-3940 4210);
PAINT MONO (-3940 4210);
FORCEPROP 0 LASTPIN (-3950 4150) $PN CC57
J 0
(-3940 4160);
DISPLAY 0.489362 (-3940 4160);
PAINT MONO (-3940 4160);
FORCEPROP 0 LASTPIN (-3950 4100) $PN CD55
J 0
(-3940 4110);
DISPLAY 0.489362 (-3940 4110);
PAINT MONO (-3940 4110);
FORCEPROP 0 LASTPIN (-3950 4050) $PN CF56
J 0
(-3940 4060);
DISPLAY 0.489362 (-3940 4060);
PAINT MONO (-3940 4060);
FORCEPROP 0 LASTPIN (-3950 4000) $PN CG55
J 0
(-3940 4010);
DISPLAY 0.489362 (-3940 4010);
PAINT MONO (-3940 4010);
FORCEPROP 0 LASTPIN (-3950 3950) $PN CG57
J 0
(-3940 3960);
DISPLAY 0.489362 (-3940 3960);
PAINT MONO (-3940 3960);
FORCEPROP 0 LASTPIN (-3950 3900) $PN CH55
J 0
(-3940 3910);
DISPLAY 0.489362 (-3940 3910);
PAINT MONO (-3940 3910);
FORCEPROP 0 LASTPIN (-3950 3800) $PN CH56
J 0
(-3940 3810);
DISPLAY 0.489362 (-3940 3810);
PAINT MONO (-3940 3810);
FORCEPROP 0 LASTPIN (-3950 3750) $PN CJ55
J 0
(-3940 3760);
DISPLAY 0.489362 (-3940 3760);
PAINT MONO (-3940 3760);
FORCEPROP 0 LASTPIN (-3950 3700) $PN CJ57
J 0
(-3940 3710);
DISPLAY 0.489362 (-3940 3710);
PAINT MONO (-3940 3710);
FORCEPROP 0 LASTPIN (-3950 3650) $PN CK55
J 0
(-3940 3660);
DISPLAY 0.489362 (-3940 3660);
PAINT MONO (-3940 3660);
FORCEPROP 0 LASTPIN (-3950 3600) $PN CM56
J 0
(-3940 3610);
DISPLAY 0.489362 (-3940 3610);
PAINT MONO (-3940 3610);
FORCEPROP 0 LASTPIN (-3950 3550) $PN CN55
J 0
(-3940 3560);
DISPLAY 0.489362 (-3940 3560);
PAINT MONO (-3940 3560);
FORCEPROP 0 LASTPIN (-3950 3500) $PN CN57
J 0
(-3940 3510);
DISPLAY 0.489362 (-3940 3510);
PAINT MONO (-3940 3510);
FORCEPROP 0 LASTPIN (-3950 3450) $PN CP55
J 0
(-3940 3460);
DISPLAY 0.489362 (-3940 3460);
PAINT MONO (-3940 3460);
FORCEPROP 0 LASTPIN (-3950 3350) $PN CP56
J 0
(-3940 3360);
DISPLAY 0.489362 (-3940 3360);
PAINT MONO (-3940 3360);
FORCEPROP 0 LASTPIN (-3950 3300) $PN CR55
J 0
(-3940 3310);
DISPLAY 0.489362 (-3940 3310);
PAINT MONO (-3940 3310);
FORCEPROP 0 LASTPIN (-3950 3250) $PN CR57
J 0
(-3940 3260);
DISPLAY 0.489362 (-3940 3260);
PAINT MONO (-3940 3260);
FORCEPROP 0 LASTPIN (-3950 3200) $PN CT55
J 0
(-3940 3210);
DISPLAY 0.489362 (-3940 3210);
PAINT MONO (-3940 3210);
FORCEPROP 0 LASTPIN (-3950 3150) $PN CV56
J 0
(-3940 3160);
DISPLAY 0.489362 (-3940 3160);
PAINT MONO (-3940 3160);
FORCEPROP 0 LASTPIN (-3950 3100) $PN CW55
J 0
(-3940 3110);
DISPLAY 0.489362 (-3940 3110);
PAINT MONO (-3940 3110);
FORCEPROP 0 LASTPIN (-3950 3050) $PN CW57
J 0
(-3940 3060);
DISPLAY 0.489362 (-3940 3060);
PAINT MONO (-3940 3060);
FORCEPROP 0 LASTPIN (-3950 3000) $PN CY55
J 0
(-3940 3010);
DISPLAY 0.489362 (-3940 3010);
PAINT MONO (-3940 3010);
FORCEPROP 0 LASTPIN (-3950 2900) $PN CY56
J 0
(-3940 2910);
DISPLAY 0.489362 (-3940 2910);
PAINT MONO (-3940 2910);
FORCEPROP 0 LASTPIN (-3950 2850) $PN DA55
J 0
(-3940 2860);
DISPLAY 0.489362 (-3940 2860);
PAINT MONO (-3940 2860);
FORCEPROP 0 LASTPIN (-3950 2800) $PN DA57
J 0
(-3940 2810);
DISPLAY 0.489362 (-3940 2810);
PAINT MONO (-3940 2810);
FORCEPROP 0 LASTPIN (-3950 2750) $PN DB55
J 0
(-3940 2760);
DISPLAY 0.489362 (-3940 2760);
PAINT MONO (-3940 2760);
FORCEPROP 0 LASTPIN (-3950 2700) $PN DD56
J 0
(-3940 2710);
DISPLAY 0.489362 (-3940 2710);
PAINT MONO (-3940 2710);
FORCEPROP 0 LASTPIN (-3950 2650) $PN DE55
J 0
(-3940 2660);
DISPLAY 0.489362 (-3940 2660);
PAINT MONO (-3940 2660);
FORCEPROP 0 LASTPIN (-3950 2600) $PN DE57
J 0
(-3940 2610);
DISPLAY 0.489362 (-3940 2610);
PAINT MONO (-3940 2610);
FORCEPROP 0 LASTPIN (-3950 2550) $PN DF55
J 0
(-3940 2560);
DISPLAY 0.489362 (-3940 2560);
PAINT MONO (-3940 2560);
FORCEPROP 0 LASTPIN (-5550 5000) $PN CD56
J 2
(-5560 5010);
DISPLAY 0.489362 (-5560 5010);
PAINT MONO (-5560 5010);
FORCEPROP 0 LASTPIN (-5550 4900) $PN CK56
J 2
(-5560 4910);
DISPLAY 0.489362 (-5560 4910);
PAINT MONO (-5560 4910);
FORCEPROP 0 LASTPIN (-5550 4800) $PN CT56
J 2
(-5560 4810);
DISPLAY 0.489362 (-5560 4810);
PAINT MONO (-5560 4810);
FORCEPROP 0 LASTPIN (-5550 4700) $PN DB56
J 2
(-5560 4710);
DISPLAY 0.489362 (-5560 4710);
PAINT MONO (-5560 4710);
FORCEPROP 0 LASTPIN (-5550 4600) $PN BY55
J 2
(-5560 4610);
DISPLAY 0.489362 (-5560 4610);
PAINT MONO (-5560 4610);
FORCEPROP 0 LASTPIN (-5550 4500) $PN CF55
J 2
(-5560 4510);
DISPLAY 0.489362 (-5560 4510);
PAINT MONO (-5560 4510);
FORCEPROP 0 LASTPIN (-5550 4400) $PN CM55
J 2
(-5560 4410);
DISPLAY 0.489362 (-5560 4410);
PAINT MONO (-5560 4410);
FORCEPROP 0 LASTPIN (-5550 4300) $PN CV55
J 2
(-5560 4310);
DISPLAY 0.489362 (-5560 4310);
PAINT MONO (-5560 4310);
FORCEPROP 0 LASTPIN (-5550 4200) $PN DD55
J 2
(-5560 4210);
DISPLAY 0.489362 (-5560 4210);
PAINT MONO (-5560 4210);
FORCEPROP 0 LASTPIN (-5550 4100) $PN BV56
J 2
(-5560 4110);
DISPLAY 0.489362 (-5560 4110);
PAINT MONO (-5560 4110);
FORCEPROP 0 LASTPIN (-5550 4950) $PN CE57
J 2
(-5560 4960);
DISPLAY 0.489362 (-5560 4960);
PAINT MONO (-5560 4960);
FORCEPROP 0 LASTPIN (-5550 4850) $PN CL57
J 2
(-5560 4860);
DISPLAY 0.489362 (-5560 4860);
PAINT MONO (-5560 4860);
FORCEPROP 0 LASTPIN (-5550 4750) $PN CU57
J 2
(-5560 4760);
DISPLAY 0.489362 (-5560 4760);
PAINT MONO (-5560 4760);
FORCEPROP 0 LASTPIN (-5550 4650) $PN DC57
J 2
(-5560 4660);
DISPLAY 0.489362 (-5560 4660);
PAINT MONO (-5560 4660);
FORCEPROP 0 LASTPIN (-5550 4550) $PN BW55
J 2
(-5560 4560);
DISPLAY 0.489362 (-5560 4560);
PAINT MONO (-5560 4560);
FORCEPROP 0 LASTPIN (-5550 4450) $PN CE55
J 2
(-5560 4460);
DISPLAY 0.489362 (-5560 4460);
PAINT MONO (-5560 4460);
FORCEPROP 0 LASTPIN (-5550 4350) $PN CL55
J 2
(-5560 4360);
DISPLAY 0.489362 (-5560 4360);
PAINT MONO (-5560 4360);
FORCEPROP 0 LASTPIN (-5550 4250) $PN CU55
J 2
(-5560 4260);
DISPLAY 0.489362 (-5560 4260);
PAINT MONO (-5560 4260);
FORCEPROP 0 LASTPIN (-5550 4150) $PN DC55
J 2
(-5560 4160);
DISPLAY 0.489362 (-5560 4160);
PAINT MONO (-5560 4160);
FORCEPROP 0 LASTPIN (-5550 4050) $PN BW57
J 2
(-5560 4060);
DISPLAY 0.489362 (-5560 4060);
PAINT MONO (-5560 4060);
FORCEPROP 0 LASTPIN (-5550 2300) $PN BL57
J 2
(-5560 2310);
DISPLAY 0.489362 (-5560 2310);
PAINT MONO (-5560 2310);
FORCEPROP 0 LASTPIN (-5550 1250) $PN BF55
J 2
(-5560 1260);
DISPLAY 0.489362 (-5560 1260);
PAINT MONO (-5560 1260);
FORCEPROP 2 LAST PART_TYPE SMLF
J 0
(-5400 6425);
DISPLAY 1.021277 (-5400 6425);
FORCEPROP 1 LAST MATERIAL IO
J 0
(-5395 6232);
DISPLAY 0.489362 (-5395 6232);
PAINT SKYBLUE (-5395 6232);
FORCEPROP 2 LAST VALUE SOCKET6096_13568-001
J 0
(-5400 6325);
DISPLAY 0.489362 (-5400 6325);
PAINT SKYBLUE (-5400 6325);
FORCEPROP 2 LAST CDS_LIB pure_quanta
J 0
(-4750 3675);
DISPLAY INVISIBLE (-4750 3675);
FORCEPROP 1 LAST CDS_LMAN_SYM_OUTLINE -650,2525,650,-2525
J 0
(-4750 3675);
DISPLAY 0.468085 (-4750 3675);
PAINT GREEN (-4750 3675);
DISPLAY INVISIBLE (-4750 3675);
FORCEPROP 1 LAST NEEDS_NO_SIZE TRUE
J 0
(-4750 3675);
DISPLAY 0.723404 (-4750 3675);
PAINT GREEN (-4750 3675);
DISPLAY INVISIBLE (-4750 3675);
FORCEPROP 1 LAST PATH I159
J 0
(-4750 3675);
DISPLAY 0.723404 (-4750 3675);
PAINT GREEN (-4750 3675);
DISPLAY INVISIBLE (-4750 3675);
FORCEPROP 1 LAST PART_NUMBER DGA^6000030
J 0
(-5395 6359);
DISPLAY 0.489362 (-5395 6359);
PAINT SKYBLUE (-5395 6359);
DISPLAY INVISIBLE (-5395 6359);
FORCEADD OFFPAGE..3
(-2750 6075);
FORCEPROP 2 LAST $XR0 100 
J 0
(-2536 6075);
DISPLAY 0.638298 (-2536 6075);
PAINT MONO (-2536 6075);
FORCEPROP 2 LAST CDS_LIB mstr_standard
J 0
(-2750 6075);
DISPLAY 0.723404 (-2750 6075);
PAINT MONO (-2750 6075);
DISPLAY INVISIBLE (-2750 6075);
FORCEPROP 1 LAST OFFPAGE TRUE
J 0
(-2425 5950);
DISPLAY 0.872340 (-2425 5950);
PAINT GREEN (-2425 5950);
DISPLAY INVISIBLE (-2425 5950);
FORCEPROP 1 LAST COMMENT_BODY TRUE
J 0
(-2800 5975);
DISPLAY 0.872340 (-2800 5975);
PAINT GREEN (-2800 5975);
DISPLAY INVISIBLE (-2800 5975);
FORCEPROP 2 LAST PATH I160
J 0
(-2525 6125);
DISPLAY 1.021277 (-2525 6125);
DISPLAY INVISIBLE (-2525 6125);
FORCEADD OFFPAGE..3
(-2750 4275);
FORCEPROP 2 LAST $XR0 100 
J 0
(-2536 4275);
DISPLAY 0.638298 (-2536 4275);
PAINT MONO (-2536 4275);
FORCEPROP 2 LAST CDS_LIB mstr_standard
J 0
(-2750 4275);
DISPLAY 0.723404 (-2750 4275);
PAINT MONO (-2750 4275);
DISPLAY INVISIBLE (-2750 4275);
FORCEPROP 1 LAST OFFPAGE TRUE
J 0
(-2425 4150);
DISPLAY 0.872340 (-2425 4150);
PAINT GREEN (-2425 4150);
DISPLAY INVISIBLE (-2425 4150);
FORCEPROP 1 LAST COMMENT_BODY TRUE
J 0
(-2800 4175);
DISPLAY 0.872340 (-2800 4175);
PAINT GREEN (-2800 4175);
DISPLAY INVISIBLE (-2800 4175);
FORCEPROP 2 LAST PATH I161
J 0
(-2525 4325);
DISPLAY 1.021277 (-2525 4325);
DISPLAY INVISIBLE (-2525 4325);
FORCEADD TAP..1
(-3475 6050);
FORCEPROP 3 LASTPIN (-3525 6050) SIG_NAME M_C_CPU1_SA_DQ<0>
J 0
(-3515 6060);
DISPLAY 0.659574 (-3515 6060);
PAINT MONO (-3515 6060);
DISPLAY INVISIBLE (-3515 6060);
FORCEPROP 1 LASTPIN (-3525 6050) BN 0
J 0
(-3537 6058);
DISPLAY 0.489362 (-3537 6058);
PAINT GREEN (-3537 6058);
FORCEPROP 2 LAST CDS_LIB mstr_standard
J 0
(-3475 6050);
DISPLAY 0.723404 (-3475 6050);
PAINT MONO (-3475 6050);
DISPLAY INVISIBLE (-3475 6050);
FORCEPROP 1 LAST BODY_TYPE PLUMBING
J 0
(-3475 6100);
DISPLAY 0.872340 (-3475 6100);
PAINT GREEN (-3475 6100);
DISPLAY INVISIBLE (-3475 6100);
FORCEPROP 1 LAST HDL_TAP TRUE
J 0
(-3150 5925);
DISPLAY 0.872340 (-3150 5925);
DISPLAY INVISIBLE (-3150 5925);
FORCEPROP 1 LAST PATH I162
J 0
(-3477 6050);
DISPLAY 0.872340 (-3477 6050);
PAINT GREEN (-3477 6050);
DISPLAY INVISIBLE (-3477 6050);
FORCEADD TAP..1
(-3475 6000);
FORCEPROP 3 LASTPIN (-3525 6000) SIG_NAME M_C_CPU1_SA_DQ<1>
J 0
(-3515 6010);
DISPLAY 0.659574 (-3515 6010);
PAINT MONO (-3515 6010);
DISPLAY INVISIBLE (-3515 6010);
FORCEPROP 1 LASTPIN (-3525 6000) BN 1
J 0
(-3537 6008);
DISPLAY 0.489362 (-3537 6008);
PAINT GREEN (-3537 6008);
FORCEPROP 2 LAST CDS_LIB mstr_standard
J 0
(-3475 6000);
DISPLAY 0.723404 (-3475 6000);
PAINT MONO (-3475 6000);
DISPLAY INVISIBLE (-3475 6000);
FORCEPROP 1 LAST BODY_TYPE PLUMBING
J 0
(-3475 6050);
DISPLAY 0.872340 (-3475 6050);
PAINT GREEN (-3475 6050);
DISPLAY INVISIBLE (-3475 6050);
FORCEPROP 1 LAST HDL_TAP TRUE
J 0
(-3150 5875);
DISPLAY 0.872340 (-3150 5875);
DISPLAY INVISIBLE (-3150 5875);
FORCEPROP 1 LAST PATH I163
J 0
(-3477 6000);
DISPLAY 0.872340 (-3477 6000);
PAINT GREEN (-3477 6000);
DISPLAY INVISIBLE (-3477 6000);
FORCEADD TAP..1
(-3475 5900);
FORCEPROP 3 LASTPIN (-3525 5900) SIG_NAME M_C_CPU1_SA_DQ<3>
J 0
(-3515 5910);
DISPLAY 0.659574 (-3515 5910);
PAINT MONO (-3515 5910);
DISPLAY INVISIBLE (-3515 5910);
FORCEPROP 1 LASTPIN (-3525 5900) BN 3
J 0
(-3537 5908);
DISPLAY 0.489362 (-3537 5908);
PAINT GREEN (-3537 5908);
FORCEPROP 2 LAST CDS_LIB mstr_standard
J 0
(-3475 5900);
DISPLAY 0.723404 (-3475 5900);
PAINT MONO (-3475 5900);
DISPLAY INVISIBLE (-3475 5900);
FORCEPROP 1 LAST BODY_TYPE PLUMBING
J 0
(-3475 5950);
DISPLAY 0.872340 (-3475 5950);
PAINT GREEN (-3475 5950);
DISPLAY INVISIBLE (-3475 5950);
FORCEPROP 1 LAST HDL_TAP TRUE
J 0
(-3150 5775);
DISPLAY 0.872340 (-3150 5775);
DISPLAY INVISIBLE (-3150 5775);
FORCEPROP 1 LAST PATH I164
J 0
(-3477 5900);
DISPLAY 0.872340 (-3477 5900);
PAINT GREEN (-3477 5900);
DISPLAY INVISIBLE (-3477 5900);
FORCEADD TAP..1
(-3475 5950);
FORCEPROP 3 LASTPIN (-3525 5950) SIG_NAME M_C_CPU1_SA_DQ<2>
J 0
(-3515 5960);
DISPLAY 0.659574 (-3515 5960);
PAINT MONO (-3515 5960);
DISPLAY INVISIBLE (-3515 5960);
FORCEPROP 1 LASTPIN (-3525 5950) BN 2
J 0
(-3537 5958);
DISPLAY 0.489362 (-3537 5958);
PAINT GREEN (-3537 5958);
FORCEPROP 2 LAST CDS_LIB mstr_standard
J 0
(-3475 5950);
DISPLAY 0.723404 (-3475 5950);
PAINT MONO (-3475 5950);
DISPLAY INVISIBLE (-3475 5950);
FORCEPROP 1 LAST BODY_TYPE PLUMBING
J 0
(-3475 6000);
DISPLAY 0.872340 (-3475 6000);
PAINT GREEN (-3475 6000);
DISPLAY INVISIBLE (-3475 6000);
FORCEPROP 1 LAST HDL_TAP TRUE
J 0
(-3150 5825);
DISPLAY 0.872340 (-3150 5825);
DISPLAY INVISIBLE (-3150 5825);
FORCEPROP 1 LAST PATH I165
J 0
(-3477 5950);
DISPLAY 0.872340 (-3477 5950);
PAINT GREEN (-3477 5950);
DISPLAY INVISIBLE (-3477 5950);
FORCEADD TAP..1
(-3475 5750);
FORCEPROP 3 LASTPIN (-3525 5750) SIG_NAME M_C_CPU1_SA_DQ<6>
J 0
(-3515 5760);
DISPLAY 0.659574 (-3515 5760);
PAINT MONO (-3515 5760);
DISPLAY INVISIBLE (-3515 5760);
FORCEPROP 1 LASTPIN (-3525 5750) BN 6
J 0
(-3537 5758);
DISPLAY 0.489362 (-3537 5758);
PAINT GREEN (-3537 5758);
FORCEPROP 2 LAST CDS_LIB mstr_standard
J 0
(-3475 5750);
DISPLAY 0.723404 (-3475 5750);
PAINT MONO (-3475 5750);
DISPLAY INVISIBLE (-3475 5750);
FORCEPROP 1 LAST BODY_TYPE PLUMBING
J 0
(-3475 5800);
DISPLAY 0.872340 (-3475 5800);
PAINT GREEN (-3475 5800);
DISPLAY INVISIBLE (-3475 5800);
FORCEPROP 1 LAST HDL_TAP TRUE
J 0
(-3150 5625);
DISPLAY 0.872340 (-3150 5625);
DISPLAY INVISIBLE (-3150 5625);
FORCEPROP 1 LAST PATH I166
J 0
(-3477 5750);
DISPLAY 0.872340 (-3477 5750);
PAINT GREEN (-3477 5750);
DISPLAY INVISIBLE (-3477 5750);
FORCEADD TAP..1
(-3475 5800);
FORCEPROP 3 LASTPIN (-3525 5800) SIG_NAME M_C_CPU1_SA_DQ<5>
J 0
(-3515 5810);
DISPLAY 0.659574 (-3515 5810);
PAINT MONO (-3515 5810);
DISPLAY INVISIBLE (-3515 5810);
FORCEPROP 1 LASTPIN (-3525 5800) BN 5
J 0
(-3537 5808);
DISPLAY 0.489362 (-3537 5808);
PAINT GREEN (-3537 5808);
FORCEPROP 2 LAST CDS_LIB mstr_standard
J 0
(-3475 5800);
DISPLAY 0.723404 (-3475 5800);
PAINT MONO (-3475 5800);
DISPLAY INVISIBLE (-3475 5800);
FORCEPROP 1 LAST BODY_TYPE PLUMBING
J 0
(-3475 5850);
DISPLAY 0.872340 (-3475 5850);
PAINT GREEN (-3475 5850);
DISPLAY INVISIBLE (-3475 5850);
FORCEPROP 1 LAST HDL_TAP TRUE
J 0
(-3150 5675);
DISPLAY 0.872340 (-3150 5675);
DISPLAY INVISIBLE (-3150 5675);
FORCEPROP 1 LAST PATH I167
J 0
(-3477 5800);
DISPLAY 0.872340 (-3477 5800);
PAINT GREEN (-3477 5800);
DISPLAY INVISIBLE (-3477 5800);
FORCEADD TAP..1
(-3475 5850);
FORCEPROP 3 LASTPIN (-3525 5850) SIG_NAME M_C_CPU1_SA_DQ<4>
J 0
(-3515 5860);
DISPLAY 0.659574 (-3515 5860);
PAINT MONO (-3515 5860);
DISPLAY INVISIBLE (-3515 5860);
FORCEPROP 1 LASTPIN (-3525 5850) BN 4
J 0
(-3537 5858);
DISPLAY 0.489362 (-3537 5858);
PAINT GREEN (-3537 5858);
FORCEPROP 2 LAST CDS_LIB mstr_standard
J 0
(-3475 5850);
DISPLAY 0.723404 (-3475 5850);
PAINT MONO (-3475 5850);
DISPLAY INVISIBLE (-3475 5850);
FORCEPROP 1 LAST BODY_TYPE PLUMBING
J 0
(-3475 5900);
DISPLAY 0.872340 (-3475 5900);
PAINT GREEN (-3475 5900);
DISPLAY INVISIBLE (-3475 5900);
FORCEPROP 1 LAST HDL_TAP TRUE
J 0
(-3150 5725);
DISPLAY 0.872340 (-3150 5725);
DISPLAY INVISIBLE (-3150 5725);
FORCEPROP 1 LAST PATH I168
J 0
(-3477 5850);
DISPLAY 0.872340 (-3477 5850);
PAINT GREEN (-3477 5850);
DISPLAY INVISIBLE (-3477 5850);
FORCEADD TAP..1
(-3475 5700);
FORCEPROP 3 LASTPIN (-3525 5700) SIG_NAME M_C_CPU1_SA_DQ<7>
J 0
(-3515 5710);
DISPLAY 0.659574 (-3515 5710);
PAINT MONO (-3515 5710);
DISPLAY INVISIBLE (-3515 5710);
FORCEPROP 1 LASTPIN (-3525 5700) BN 7
J 0
(-3537 5708);
DISPLAY 0.489362 (-3537 5708);
PAINT GREEN (-3537 5708);
FORCEPROP 2 LAST CDS_LIB mstr_standard
J 0
(-3475 5700);
DISPLAY 0.723404 (-3475 5700);
PAINT MONO (-3475 5700);
DISPLAY INVISIBLE (-3475 5700);
FORCEPROP 1 LAST BODY_TYPE PLUMBING
J 0
(-3475 5750);
DISPLAY 0.872340 (-3475 5750);
PAINT GREEN (-3475 5750);
DISPLAY INVISIBLE (-3475 5750);
FORCEPROP 1 LAST HDL_TAP TRUE
J 0
(-3150 5575);
DISPLAY 0.872340 (-3150 5575);
DISPLAY INVISIBLE (-3150 5575);
FORCEPROP 1 LAST PATH I169
J 0
(-3477 5700);
DISPLAY 0.872340 (-3477 5700);
PAINT GREEN (-3477 5700);
DISPLAY INVISIBLE (-3477 5700);
FORCEADD TAP..1
(-3475 5550);
FORCEPROP 3 LASTPIN (-3525 5550) SIG_NAME M_C_CPU1_SA_DQ<9>
J 0
(-3515 5560);
DISPLAY 0.659574 (-3515 5560);
PAINT MONO (-3515 5560);
DISPLAY INVISIBLE (-3515 5560);
FORCEPROP 1 LASTPIN (-3525 5550) BN 9
J 0
(-3537 5558);
DISPLAY 0.489362 (-3537 5558);
PAINT GREEN (-3537 5558);
FORCEPROP 2 LAST CDS_LIB mstr_standard
J 0
(-3475 5550);
DISPLAY 0.723404 (-3475 5550);
PAINT MONO (-3475 5550);
DISPLAY INVISIBLE (-3475 5550);
FORCEPROP 1 LAST BODY_TYPE PLUMBING
J 0
(-3475 5600);
DISPLAY 0.872340 (-3475 5600);
PAINT GREEN (-3475 5600);
DISPLAY INVISIBLE (-3475 5600);
FORCEPROP 1 LAST HDL_TAP TRUE
J 0
(-3150 5425);
DISPLAY 0.872340 (-3150 5425);
DISPLAY INVISIBLE (-3150 5425);
FORCEPROP 1 LAST PATH I170
J 0
(-3477 5550);
DISPLAY 0.872340 (-3477 5550);
PAINT GREEN (-3477 5550);
DISPLAY INVISIBLE (-3477 5550);
FORCEADD TAP..1
(-3475 5600);
FORCEPROP 3 LASTPIN (-3525 5600) SIG_NAME M_C_CPU1_SA_DQ<8>
J 0
(-3515 5610);
DISPLAY 0.659574 (-3515 5610);
PAINT MONO (-3515 5610);
DISPLAY INVISIBLE (-3515 5610);
FORCEPROP 1 LASTPIN (-3525 5600) BN 8
J 0
(-3537 5608);
DISPLAY 0.489362 (-3537 5608);
PAINT GREEN (-3537 5608);
FORCEPROP 2 LAST CDS_LIB mstr_standard
J 0
(-3475 5600);
DISPLAY 0.723404 (-3475 5600);
PAINT MONO (-3475 5600);
DISPLAY INVISIBLE (-3475 5600);
FORCEPROP 1 LAST BODY_TYPE PLUMBING
J 0
(-3475 5650);
DISPLAY 0.872340 (-3475 5650);
PAINT GREEN (-3475 5650);
DISPLAY INVISIBLE (-3475 5650);
FORCEPROP 1 LAST HDL_TAP TRUE
J 0
(-3150 5475);
DISPLAY 0.872340 (-3150 5475);
DISPLAY INVISIBLE (-3150 5475);
FORCEPROP 1 LAST PATH I171
J 0
(-3477 5600);
DISPLAY 0.872340 (-3477 5600);
PAINT GREEN (-3477 5600);
DISPLAY INVISIBLE (-3477 5600);
FORCEADD TAP..1
(-3475 5500);
FORCEPROP 3 LASTPIN (-3525 5500) SIG_NAME M_C_CPU1_SA_DQ<10>
J 0
(-3515 5510);
DISPLAY 0.659574 (-3515 5510);
PAINT MONO (-3515 5510);
DISPLAY INVISIBLE (-3515 5510);
FORCEPROP 1 LASTPIN (-3525 5500) BN 10
J 0
(-3537 5508);
DISPLAY 0.489362 (-3537 5508);
PAINT GREEN (-3537 5508);
FORCEPROP 2 LAST CDS_LIB mstr_standard
J 0
(-3475 5500);
DISPLAY 0.723404 (-3475 5500);
PAINT MONO (-3475 5500);
DISPLAY INVISIBLE (-3475 5500);
FORCEPROP 1 LAST BODY_TYPE PLUMBING
J 0
(-3475 5550);
DISPLAY 0.872340 (-3475 5550);
PAINT GREEN (-3475 5550);
DISPLAY INVISIBLE (-3475 5550);
FORCEPROP 1 LAST HDL_TAP TRUE
J 0
(-3150 5375);
DISPLAY 0.872340 (-3150 5375);
DISPLAY INVISIBLE (-3150 5375);
FORCEPROP 1 LAST PATH I172
J 0
(-3477 5500);
DISPLAY 0.872340 (-3477 5500);
PAINT GREEN (-3477 5500);
DISPLAY INVISIBLE (-3477 5500);
FORCEADD TAP..1
(-3475 5400);
FORCEPROP 3 LASTPIN (-3525 5400) SIG_NAME M_C_CPU1_SA_DQ<12>
J 0
(-3515 5410);
DISPLAY 0.659574 (-3515 5410);
PAINT MONO (-3515 5410);
DISPLAY INVISIBLE (-3515 5410);
FORCEPROP 1 LASTPIN (-3525 5400) BN 12
J 0
(-3537 5408);
DISPLAY 0.489362 (-3537 5408);
PAINT GREEN (-3537 5408);
FORCEPROP 2 LAST CDS_LIB mstr_standard
J 0
(-3475 5400);
DISPLAY 0.723404 (-3475 5400);
PAINT MONO (-3475 5400);
DISPLAY INVISIBLE (-3475 5400);
FORCEPROP 1 LAST BODY_TYPE PLUMBING
J 0
(-3475 5450);
DISPLAY 0.872340 (-3475 5450);
PAINT GREEN (-3475 5450);
DISPLAY INVISIBLE (-3475 5450);
FORCEPROP 1 LAST HDL_TAP TRUE
J 0
(-3150 5275);
DISPLAY 0.872340 (-3150 5275);
DISPLAY INVISIBLE (-3150 5275);
FORCEPROP 1 LAST PATH I173
J 0
(-3477 5400);
DISPLAY 0.872340 (-3477 5400);
PAINT GREEN (-3477 5400);
DISPLAY INVISIBLE (-3477 5400);
FORCEADD TAP..1
(-3475 5450);
FORCEPROP 3 LASTPIN (-3525 5450) SIG_NAME M_C_CPU1_SA_DQ<11>
J 0
(-3515 5460);
DISPLAY 0.659574 (-3515 5460);
PAINT MONO (-3515 5460);
DISPLAY INVISIBLE (-3515 5460);
FORCEPROP 1 LASTPIN (-3525 5450) BN 11
J 0
(-3537 5458);
DISPLAY 0.489362 (-3537 5458);
PAINT GREEN (-3537 5458);
FORCEPROP 2 LAST CDS_LIB mstr_standard
J 0
(-3475 5450);
DISPLAY 0.723404 (-3475 5450);
PAINT MONO (-3475 5450);
DISPLAY INVISIBLE (-3475 5450);
FORCEPROP 1 LAST BODY_TYPE PLUMBING
J 0
(-3475 5500);
DISPLAY 0.872340 (-3475 5500);
PAINT GREEN (-3475 5500);
DISPLAY INVISIBLE (-3475 5500);
FORCEPROP 1 LAST HDL_TAP TRUE
J 0
(-3150 5325);
DISPLAY 0.872340 (-3150 5325);
DISPLAY INVISIBLE (-3150 5325);
FORCEPROP 1 LAST PATH I174
J 0
(-3477 5450);
DISPLAY 0.872340 (-3477 5450);
PAINT GREEN (-3477 5450);
DISPLAY INVISIBLE (-3477 5450);
FORCEADD TAP..1
(-3475 5350);
FORCEPROP 3 LASTPIN (-3525 5350) SIG_NAME M_C_CPU1_SA_DQ<13>
J 0
(-3515 5360);
DISPLAY 0.659574 (-3515 5360);
PAINT MONO (-3515 5360);
DISPLAY INVISIBLE (-3515 5360);
FORCEPROP 1 LASTPIN (-3525 5350) BN 13
J 0
(-3537 5358);
DISPLAY 0.489362 (-3537 5358);
PAINT GREEN (-3537 5358);
FORCEPROP 2 LAST CDS_LIB mstr_standard
J 0
(-3475 5350);
DISPLAY 0.723404 (-3475 5350);
PAINT MONO (-3475 5350);
DISPLAY INVISIBLE (-3475 5350);
FORCEPROP 1 LAST BODY_TYPE PLUMBING
J 0
(-3475 5400);
DISPLAY 0.872340 (-3475 5400);
PAINT GREEN (-3475 5400);
DISPLAY INVISIBLE (-3475 5400);
FORCEPROP 1 LAST HDL_TAP TRUE
J 0
(-3150 5225);
DISPLAY 0.872340 (-3150 5225);
DISPLAY INVISIBLE (-3150 5225);
FORCEPROP 1 LAST PATH I175
J 0
(-3477 5350);
DISPLAY 0.872340 (-3477 5350);
PAINT GREEN (-3477 5350);
DISPLAY INVISIBLE (-3477 5350);
FORCEADD TAP..1
(-3475 5300);
FORCEPROP 3 LASTPIN (-3525 5300) SIG_NAME M_C_CPU1_SA_DQ<14>
J 0
(-3515 5310);
DISPLAY 0.659574 (-3515 5310);
PAINT MONO (-3515 5310);
DISPLAY INVISIBLE (-3515 5310);
FORCEPROP 1 LASTPIN (-3525 5300) BN 14
J 0
(-3537 5308);
DISPLAY 0.489362 (-3537 5308);
PAINT GREEN (-3537 5308);
FORCEPROP 2 LAST CDS_LIB mstr_standard
J 0
(-3475 5300);
DISPLAY 0.723404 (-3475 5300);
PAINT MONO (-3475 5300);
DISPLAY INVISIBLE (-3475 5300);
FORCEPROP 1 LAST BODY_TYPE PLUMBING
J 0
(-3475 5350);
DISPLAY 0.872340 (-3475 5350);
PAINT GREEN (-3475 5350);
DISPLAY INVISIBLE (-3475 5350);
FORCEPROP 1 LAST HDL_TAP TRUE
J 0
(-3150 5175);
DISPLAY 0.872340 (-3150 5175);
DISPLAY INVISIBLE (-3150 5175);
FORCEPROP 1 LAST PATH I176
J 0
(-3477 5300);
DISPLAY 0.872340 (-3477 5300);
PAINT GREEN (-3477 5300);
DISPLAY INVISIBLE (-3477 5300);
FORCEADD TAP..1
(-3475 5250);
FORCEPROP 3 LASTPIN (-3525 5250) SIG_NAME M_C_CPU1_SA_DQ<15>
J 0
(-3515 5260);
DISPLAY 0.659574 (-3515 5260);
PAINT MONO (-3515 5260);
DISPLAY INVISIBLE (-3515 5260);
FORCEPROP 1 LASTPIN (-3525 5250) BN 15
J 0
(-3537 5258);
DISPLAY 0.489362 (-3537 5258);
PAINT GREEN (-3537 5258);
FORCEPROP 2 LAST CDS_LIB mstr_standard
J 0
(-3475 5250);
DISPLAY 0.723404 (-3475 5250);
PAINT MONO (-3475 5250);
DISPLAY INVISIBLE (-3475 5250);
FORCEPROP 1 LAST BODY_TYPE PLUMBING
J 0
(-3475 5300);
DISPLAY 0.872340 (-3475 5300);
PAINT GREEN (-3475 5300);
DISPLAY INVISIBLE (-3475 5300);
FORCEPROP 1 LAST HDL_TAP TRUE
J 0
(-3150 5125);
DISPLAY 0.872340 (-3150 5125);
DISPLAY INVISIBLE (-3150 5125);
FORCEPROP 1 LAST PATH I177
J 0
(-3477 5250);
DISPLAY 0.872340 (-3477 5250);
PAINT GREEN (-3477 5250);
DISPLAY INVISIBLE (-3477 5250);
FORCEADD TAP..1
(-3475 5150);
FORCEPROP 3 LASTPIN (-3525 5150) SIG_NAME M_C_CPU1_SA_DQ<16>
J 0
(-3515 5160);
DISPLAY 0.659574 (-3515 5160);
PAINT MONO (-3515 5160);
DISPLAY INVISIBLE (-3515 5160);
FORCEPROP 1 LASTPIN (-3525 5150) BN 16
J 0
(-3537 5158);
DISPLAY 0.489362 (-3537 5158);
PAINT GREEN (-3537 5158);
FORCEPROP 2 LAST CDS_LIB mstr_standard
J 0
(-3475 5150);
DISPLAY 0.723404 (-3475 5150);
PAINT MONO (-3475 5150);
DISPLAY INVISIBLE (-3475 5150);
FORCEPROP 1 LAST BODY_TYPE PLUMBING
J 0
(-3475 5200);
DISPLAY 0.872340 (-3475 5200);
PAINT GREEN (-3475 5200);
DISPLAY INVISIBLE (-3475 5200);
FORCEPROP 1 LAST HDL_TAP TRUE
J 0
(-3150 5025);
DISPLAY 0.872340 (-3150 5025);
DISPLAY INVISIBLE (-3150 5025);
FORCEPROP 1 LAST PATH I178
J 0
(-3477 5150);
DISPLAY 0.872340 (-3477 5150);
PAINT GREEN (-3477 5150);
DISPLAY INVISIBLE (-3477 5150);
FORCEADD TAP..1
(-3475 5000);
FORCEPROP 3 LASTPIN (-3525 5000) SIG_NAME M_C_CPU1_SA_DQ<19>
J 0
(-3515 5010);
DISPLAY 0.659574 (-3515 5010);
PAINT MONO (-3515 5010);
DISPLAY INVISIBLE (-3515 5010);
FORCEPROP 1 LASTPIN (-3525 5000) BN 19
J 0
(-3537 5008);
DISPLAY 0.489362 (-3537 5008);
PAINT GREEN (-3537 5008);
FORCEPROP 2 LAST CDS_LIB mstr_standard
J 0
(-3475 5000);
DISPLAY 0.723404 (-3475 5000);
PAINT MONO (-3475 5000);
DISPLAY INVISIBLE (-3475 5000);
FORCEPROP 1 LAST BODY_TYPE PLUMBING
J 0
(-3475 5050);
DISPLAY 0.872340 (-3475 5050);
PAINT GREEN (-3475 5050);
DISPLAY INVISIBLE (-3475 5050);
FORCEPROP 1 LAST HDL_TAP TRUE
J 0
(-3150 4875);
DISPLAY 0.872340 (-3150 4875);
DISPLAY INVISIBLE (-3150 4875);
FORCEPROP 1 LAST PATH I179
J 0
(-3477 5000);
DISPLAY 0.872340 (-3477 5000);
PAINT GREEN (-3477 5000);
DISPLAY INVISIBLE (-3477 5000);
FORCEADD TAP..1
(-3475 5050);
FORCEPROP 3 LASTPIN (-3525 5050) SIG_NAME M_C_CPU1_SA_DQ<18>
J 0
(-3515 5060);
DISPLAY 0.659574 (-3515 5060);
PAINT MONO (-3515 5060);
DISPLAY INVISIBLE (-3515 5060);
FORCEPROP 1 LASTPIN (-3525 5050) BN 18
J 0
(-3537 5058);
DISPLAY 0.489362 (-3537 5058);
PAINT GREEN (-3537 5058);
FORCEPROP 2 LAST CDS_LIB mstr_standard
J 0
(-3475 5050);
DISPLAY 0.723404 (-3475 5050);
PAINT MONO (-3475 5050);
DISPLAY INVISIBLE (-3475 5050);
FORCEPROP 1 LAST BODY_TYPE PLUMBING
J 0
(-3475 5100);
DISPLAY 0.872340 (-3475 5100);
PAINT GREEN (-3475 5100);
DISPLAY INVISIBLE (-3475 5100);
FORCEPROP 1 LAST HDL_TAP TRUE
J 0
(-3150 4925);
DISPLAY 0.872340 (-3150 4925);
DISPLAY INVISIBLE (-3150 4925);
FORCEPROP 1 LAST PATH I180
J 0
(-3477 5050);
DISPLAY 0.872340 (-3477 5050);
PAINT GREEN (-3477 5050);
DISPLAY INVISIBLE (-3477 5050);
FORCEADD TAP..1
(-3475 5100);
FORCEPROP 3 LASTPIN (-3525 5100) SIG_NAME M_C_CPU1_SA_DQ<17>
J 0
(-3515 5110);
DISPLAY 0.659574 (-3515 5110);
PAINT MONO (-3515 5110);
DISPLAY INVISIBLE (-3515 5110);
FORCEPROP 1 LASTPIN (-3525 5100) BN 17
J 0
(-3537 5108);
DISPLAY 0.489362 (-3537 5108);
PAINT GREEN (-3537 5108);
FORCEPROP 2 LAST CDS_LIB mstr_standard
J 0
(-3475 5100);
DISPLAY 0.723404 (-3475 5100);
PAINT MONO (-3475 5100);
DISPLAY INVISIBLE (-3475 5100);
FORCEPROP 1 LAST BODY_TYPE PLUMBING
J 0
(-3475 5150);
DISPLAY 0.872340 (-3475 5150);
PAINT GREEN (-3475 5150);
DISPLAY INVISIBLE (-3475 5150);
FORCEPROP 1 LAST HDL_TAP TRUE
J 0
(-3150 4975);
DISPLAY 0.872340 (-3150 4975);
DISPLAY INVISIBLE (-3150 4975);
FORCEPROP 1 LAST PATH I181
J 0
(-3477 5100);
DISPLAY 0.872340 (-3477 5100);
PAINT GREEN (-3477 5100);
DISPLAY INVISIBLE (-3477 5100);
FORCEADD TAP..1
(-3475 4900);
FORCEPROP 3 LASTPIN (-3525 4900) SIG_NAME M_C_CPU1_SA_DQ<21>
J 0
(-3515 4910);
DISPLAY 0.659574 (-3515 4910);
PAINT MONO (-3515 4910);
DISPLAY INVISIBLE (-3515 4910);
FORCEPROP 1 LASTPIN (-3525 4900) BN 21
J 0
(-3537 4908);
DISPLAY 0.489362 (-3537 4908);
PAINT GREEN (-3537 4908);
FORCEPROP 2 LAST CDS_LIB mstr_standard
J 0
(-3475 4900);
DISPLAY 0.723404 (-3475 4900);
PAINT MONO (-3475 4900);
DISPLAY INVISIBLE (-3475 4900);
FORCEPROP 1 LAST BODY_TYPE PLUMBING
J 0
(-3475 4950);
DISPLAY 0.872340 (-3475 4950);
PAINT GREEN (-3475 4950);
DISPLAY INVISIBLE (-3475 4950);
FORCEPROP 1 LAST HDL_TAP TRUE
J 0
(-3150 4775);
DISPLAY 0.872340 (-3150 4775);
DISPLAY INVISIBLE (-3150 4775);
FORCEPROP 1 LAST PATH I182
J 0
(-3477 4900);
DISPLAY 0.872340 (-3477 4900);
PAINT GREEN (-3477 4900);
DISPLAY INVISIBLE (-3477 4900);
FORCEADD TAP..1
(-3475 4950);
FORCEPROP 3 LASTPIN (-3525 4950) SIG_NAME M_C_CPU1_SA_DQ<20>
J 0
(-3515 4960);
DISPLAY 0.659574 (-3515 4960);
PAINT MONO (-3515 4960);
DISPLAY INVISIBLE (-3515 4960);
FORCEPROP 1 LASTPIN (-3525 4950) BN 20
J 0
(-3537 4958);
DISPLAY 0.489362 (-3537 4958);
PAINT GREEN (-3537 4958);
FORCEPROP 2 LAST CDS_LIB mstr_standard
J 0
(-3475 4950);
DISPLAY 0.723404 (-3475 4950);
PAINT MONO (-3475 4950);
DISPLAY INVISIBLE (-3475 4950);
FORCEPROP 1 LAST BODY_TYPE PLUMBING
J 0
(-3475 5000);
DISPLAY 0.872340 (-3475 5000);
PAINT GREEN (-3475 5000);
DISPLAY INVISIBLE (-3475 5000);
FORCEPROP 1 LAST HDL_TAP TRUE
J 0
(-3150 4825);
DISPLAY 0.872340 (-3150 4825);
DISPLAY INVISIBLE (-3150 4825);
FORCEPROP 1 LAST PATH I183
J 0
(-3477 4950);
DISPLAY 0.872340 (-3477 4950);
PAINT GREEN (-3477 4950);
DISPLAY INVISIBLE (-3477 4950);
FORCEADD TAP..1
(-3475 4800);
FORCEPROP 3 LASTPIN (-3525 4800) SIG_NAME M_C_CPU1_SA_DQ<23>
J 0
(-3515 4810);
DISPLAY 0.659574 (-3515 4810);
PAINT MONO (-3515 4810);
DISPLAY INVISIBLE (-3515 4810);
FORCEPROP 1 LASTPIN (-3525 4800) BN 23
J 0
(-3537 4808);
DISPLAY 0.489362 (-3537 4808);
PAINT GREEN (-3537 4808);
FORCEPROP 2 LAST CDS_LIB mstr_standard
J 0
(-3475 4800);
DISPLAY 0.723404 (-3475 4800);
PAINT MONO (-3475 4800);
DISPLAY INVISIBLE (-3475 4800);
FORCEPROP 1 LAST BODY_TYPE PLUMBING
J 0
(-3475 4850);
DISPLAY 0.872340 (-3475 4850);
PAINT GREEN (-3475 4850);
DISPLAY INVISIBLE (-3475 4850);
FORCEPROP 1 LAST HDL_TAP TRUE
J 0
(-3150 4675);
DISPLAY 0.872340 (-3150 4675);
DISPLAY INVISIBLE (-3150 4675);
FORCEPROP 1 LAST PATH I184
J 0
(-3477 4800);
DISPLAY 0.872340 (-3477 4800);
PAINT GREEN (-3477 4800);
DISPLAY INVISIBLE (-3477 4800);
FORCEADD TAP..1
(-3475 4850);
FORCEPROP 3 LASTPIN (-3525 4850) SIG_NAME M_C_CPU1_SA_DQ<22>
J 0
(-3515 4860);
DISPLAY 0.659574 (-3515 4860);
PAINT MONO (-3515 4860);
DISPLAY INVISIBLE (-3515 4860);
FORCEPROP 1 LASTPIN (-3525 4850) BN 22
J 0
(-3537 4858);
DISPLAY 0.489362 (-3537 4858);
PAINT GREEN (-3537 4858);
FORCEPROP 2 LAST CDS_LIB mstr_standard
J 0
(-3475 4850);
DISPLAY 0.723404 (-3475 4850);
PAINT MONO (-3475 4850);
DISPLAY INVISIBLE (-3475 4850);
FORCEPROP 1 LAST BODY_TYPE PLUMBING
J 0
(-3475 4900);
DISPLAY 0.872340 (-3475 4900);
PAINT GREEN (-3475 4900);
DISPLAY INVISIBLE (-3475 4900);
FORCEPROP 1 LAST HDL_TAP TRUE
J 0
(-3150 4725);
DISPLAY 0.872340 (-3150 4725);
DISPLAY INVISIBLE (-3150 4725);
FORCEPROP 1 LAST PATH I185
J 0
(-3477 4850);
DISPLAY 0.872340 (-3477 4850);
PAINT GREEN (-3477 4850);
DISPLAY INVISIBLE (-3477 4850);
FORCEADD TAP..1
(-3475 4650);
FORCEPROP 3 LASTPIN (-3525 4650) SIG_NAME M_C_CPU1_SA_DQ<25>
J 0
(-3515 4660);
DISPLAY 0.659574 (-3515 4660);
PAINT MONO (-3515 4660);
DISPLAY INVISIBLE (-3515 4660);
FORCEPROP 1 LASTPIN (-3525 4650) BN 25
J 0
(-3537 4658);
DISPLAY 0.489362 (-3537 4658);
PAINT GREEN (-3537 4658);
FORCEPROP 2 LAST CDS_LIB mstr_standard
J 0
(-3475 4650);
DISPLAY 0.723404 (-3475 4650);
PAINT MONO (-3475 4650);
DISPLAY INVISIBLE (-3475 4650);
FORCEPROP 1 LAST BODY_TYPE PLUMBING
J 0
(-3475 4700);
DISPLAY 0.872340 (-3475 4700);
PAINT GREEN (-3475 4700);
DISPLAY INVISIBLE (-3475 4700);
FORCEPROP 1 LAST HDL_TAP TRUE
J 0
(-3150 4525);
DISPLAY 0.872340 (-3150 4525);
DISPLAY INVISIBLE (-3150 4525);
FORCEPROP 1 LAST PATH I186
J 0
(-3477 4650);
DISPLAY 0.872340 (-3477 4650);
PAINT GREEN (-3477 4650);
DISPLAY INVISIBLE (-3477 4650);
FORCEADD TAP..1
(-3475 4700);
FORCEPROP 3 LASTPIN (-3525 4700) SIG_NAME M_C_CPU1_SA_DQ<24>
J 0
(-3515 4710);
DISPLAY 0.659574 (-3515 4710);
PAINT MONO (-3515 4710);
DISPLAY INVISIBLE (-3515 4710);
FORCEPROP 1 LASTPIN (-3525 4700) BN 24
J 0
(-3537 4708);
DISPLAY 0.489362 (-3537 4708);
PAINT GREEN (-3537 4708);
FORCEPROP 2 LAST CDS_LIB mstr_standard
J 0
(-3475 4700);
DISPLAY 0.723404 (-3475 4700);
PAINT MONO (-3475 4700);
DISPLAY INVISIBLE (-3475 4700);
FORCEPROP 1 LAST BODY_TYPE PLUMBING
J 0
(-3475 4750);
DISPLAY 0.872340 (-3475 4750);
PAINT GREEN (-3475 4750);
DISPLAY INVISIBLE (-3475 4750);
FORCEPROP 1 LAST HDL_TAP TRUE
J 0
(-3150 4575);
DISPLAY 0.872340 (-3150 4575);
DISPLAY INVISIBLE (-3150 4575);
FORCEPROP 1 LAST PATH I187
J 0
(-3477 4700);
DISPLAY 0.872340 (-3477 4700);
PAINT GREEN (-3477 4700);
DISPLAY INVISIBLE (-3477 4700);
FORCEADD TAP..1
(-3475 4600);
FORCEPROP 3 LASTPIN (-3525 4600) SIG_NAME M_C_CPU1_SA_DQ<26>
J 0
(-3515 4610);
DISPLAY 0.659574 (-3515 4610);
PAINT MONO (-3515 4610);
DISPLAY INVISIBLE (-3515 4610);
FORCEPROP 1 LASTPIN (-3525 4600) BN 26
J 0
(-3537 4608);
DISPLAY 0.489362 (-3537 4608);
PAINT GREEN (-3537 4608);
FORCEPROP 2 LAST CDS_LIB mstr_standard
J 0
(-3475 4600);
DISPLAY 0.723404 (-3475 4600);
PAINT MONO (-3475 4600);
DISPLAY INVISIBLE (-3475 4600);
FORCEPROP 1 LAST BODY_TYPE PLUMBING
J 0
(-3475 4650);
DISPLAY 0.872340 (-3475 4650);
PAINT GREEN (-3475 4650);
DISPLAY INVISIBLE (-3475 4650);
FORCEPROP 1 LAST HDL_TAP TRUE
J 0
(-3150 4475);
DISPLAY 0.872340 (-3150 4475);
DISPLAY INVISIBLE (-3150 4475);
FORCEPROP 1 LAST PATH I188
J 0
(-3477 4600);
DISPLAY 0.872340 (-3477 4600);
PAINT GREEN (-3477 4600);
DISPLAY INVISIBLE (-3477 4600);
FORCEADD TAP..1
(-3475 4500);
FORCEPROP 3 LASTPIN (-3525 4500) SIG_NAME M_C_CPU1_SA_DQ<28>
J 0
(-3515 4510);
DISPLAY 0.659574 (-3515 4510);
PAINT MONO (-3515 4510);
DISPLAY INVISIBLE (-3515 4510);
FORCEPROP 1 LASTPIN (-3525 4500) BN 28
J 0
(-3537 4508);
DISPLAY 0.489362 (-3537 4508);
PAINT GREEN (-3537 4508);
FORCEPROP 2 LAST CDS_LIB mstr_standard
J 0
(-3475 4500);
DISPLAY 0.723404 (-3475 4500);
PAINT MONO (-3475 4500);
DISPLAY INVISIBLE (-3475 4500);
FORCEPROP 1 LAST BODY_TYPE PLUMBING
J 0
(-3475 4550);
DISPLAY 0.872340 (-3475 4550);
PAINT GREEN (-3475 4550);
DISPLAY INVISIBLE (-3475 4550);
FORCEPROP 1 LAST HDL_TAP TRUE
J 0
(-3150 4375);
DISPLAY 0.872340 (-3150 4375);
DISPLAY INVISIBLE (-3150 4375);
FORCEPROP 1 LAST PATH I189
J 0
(-3477 4500);
DISPLAY 0.872340 (-3477 4500);
PAINT GREEN (-3477 4500);
DISPLAY INVISIBLE (-3477 4500);
FORCEADD TAP..1
(-3475 4550);
FORCEPROP 3 LASTPIN (-3525 4550) SIG_NAME M_C_CPU1_SA_DQ<27>
J 0
(-3515 4560);
DISPLAY 0.659574 (-3515 4560);
PAINT MONO (-3515 4560);
DISPLAY INVISIBLE (-3515 4560);
FORCEPROP 1 LASTPIN (-3525 4550) BN 27
J 0
(-3537 4558);
DISPLAY 0.489362 (-3537 4558);
PAINT GREEN (-3537 4558);
FORCEPROP 2 LAST CDS_LIB mstr_standard
J 0
(-3475 4550);
DISPLAY 0.723404 (-3475 4550);
PAINT MONO (-3475 4550);
DISPLAY INVISIBLE (-3475 4550);
FORCEPROP 1 LAST BODY_TYPE PLUMBING
J 0
(-3475 4600);
DISPLAY 0.872340 (-3475 4600);
PAINT GREEN (-3475 4600);
DISPLAY INVISIBLE (-3475 4600);
FORCEPROP 1 LAST HDL_TAP TRUE
J 0
(-3150 4425);
DISPLAY 0.872340 (-3150 4425);
DISPLAY INVISIBLE (-3150 4425);
FORCEPROP 1 LAST PATH I190
J 0
(-3477 4550);
DISPLAY 0.872340 (-3477 4550);
PAINT GREEN (-3477 4550);
DISPLAY INVISIBLE (-3477 4550);
FORCEADD TAP..1
(-3475 4400);
FORCEPROP 3 LASTPIN (-3525 4400) SIG_NAME M_C_CPU1_SA_DQ<30>
J 0
(-3515 4410);
DISPLAY 0.659574 (-3515 4410);
PAINT MONO (-3515 4410);
DISPLAY INVISIBLE (-3515 4410);
FORCEPROP 1 LASTPIN (-3525 4400) BN 30
J 0
(-3537 4408);
DISPLAY 0.489362 (-3537 4408);
PAINT GREEN (-3537 4408);
FORCEPROP 2 LAST CDS_LIB mstr_standard
J 0
(-3475 4400);
DISPLAY 0.723404 (-3475 4400);
PAINT MONO (-3475 4400);
DISPLAY INVISIBLE (-3475 4400);
FORCEPROP 1 LAST BODY_TYPE PLUMBING
J 0
(-3475 4450);
DISPLAY 0.872340 (-3475 4450);
PAINT GREEN (-3475 4450);
DISPLAY INVISIBLE (-3475 4450);
FORCEPROP 1 LAST HDL_TAP TRUE
J 0
(-3150 4275);
DISPLAY 0.872340 (-3150 4275);
DISPLAY INVISIBLE (-3150 4275);
FORCEPROP 1 LAST PATH I191
J 0
(-3477 4400);
DISPLAY 0.872340 (-3477 4400);
PAINT GREEN (-3477 4400);
DISPLAY INVISIBLE (-3477 4400);
FORCEADD TAP..1
(-3475 4450);
FORCEPROP 3 LASTPIN (-3525 4450) SIG_NAME M_C_CPU1_SA_DQ<29>
J 0
(-3515 4460);
DISPLAY 0.659574 (-3515 4460);
PAINT MONO (-3515 4460);
DISPLAY INVISIBLE (-3515 4460);
FORCEPROP 1 LASTPIN (-3525 4450) BN 29
J 0
(-3537 4458);
DISPLAY 0.489362 (-3537 4458);
PAINT GREEN (-3537 4458);
FORCEPROP 2 LAST CDS_LIB mstr_standard
J 0
(-3475 4450);
DISPLAY 0.723404 (-3475 4450);
PAINT MONO (-3475 4450);
DISPLAY INVISIBLE (-3475 4450);
FORCEPROP 1 LAST BODY_TYPE PLUMBING
J 0
(-3475 4500);
DISPLAY 0.872340 (-3475 4500);
PAINT GREEN (-3475 4500);
DISPLAY INVISIBLE (-3475 4500);
FORCEPROP 1 LAST HDL_TAP TRUE
J 0
(-3150 4325);
DISPLAY 0.872340 (-3150 4325);
DISPLAY INVISIBLE (-3150 4325);
FORCEPROP 1 LAST PATH I192
J 0
(-3477 4450);
DISPLAY 0.872340 (-3477 4450);
PAINT GREEN (-3477 4450);
DISPLAY INVISIBLE (-3477 4450);
FORCEADD TAP..1
(-3475 4350);
FORCEPROP 3 LASTPIN (-3525 4350) SIG_NAME M_C_CPU1_SA_DQ<31>
J 0
(-3515 4360);
DISPLAY 0.659574 (-3515 4360);
PAINT MONO (-3515 4360);
DISPLAY INVISIBLE (-3515 4360);
FORCEPROP 1 LASTPIN (-3525 4350) BN 31
J 0
(-3537 4358);
DISPLAY 0.489362 (-3537 4358);
PAINT GREEN (-3537 4358);
FORCEPROP 2 LAST CDS_LIB mstr_standard
J 0
(-3475 4350);
DISPLAY 0.723404 (-3475 4350);
PAINT MONO (-3475 4350);
DISPLAY INVISIBLE (-3475 4350);
FORCEPROP 1 LAST BODY_TYPE PLUMBING
J 0
(-3475 4400);
DISPLAY 0.872340 (-3475 4400);
PAINT GREEN (-3475 4400);
DISPLAY INVISIBLE (-3475 4400);
FORCEPROP 1 LAST HDL_TAP TRUE
J 0
(-3150 4225);
DISPLAY 0.872340 (-3150 4225);
DISPLAY INVISIBLE (-3150 4225);
FORCEPROP 1 LAST PATH I193
J 0
(-3477 4350);
DISPLAY 0.872340 (-3477 4350);
PAINT GREEN (-3477 4350);
DISPLAY INVISIBLE (-3477 4350);
FORCEADD TAP..1
(-3475 4250);
FORCEPROP 3 LASTPIN (-3525 4250) SIG_NAME M_C_CPU1_SB_DQ<0>
J 0
(-3515 4260);
DISPLAY 0.659574 (-3515 4260);
PAINT MONO (-3515 4260);
DISPLAY INVISIBLE (-3515 4260);
FORCEPROP 1 LASTPIN (-3525 4250) BN 0
J 0
(-3537 4258);
DISPLAY 0.489362 (-3537 4258);
PAINT GREEN (-3537 4258);
FORCEPROP 2 LAST CDS_LIB mstr_standard
J 0
(-3475 4250);
DISPLAY 0.723404 (-3475 4250);
PAINT MONO (-3475 4250);
DISPLAY INVISIBLE (-3475 4250);
FORCEPROP 1 LAST BODY_TYPE PLUMBING
J 0
(-3475 4300);
DISPLAY 0.872340 (-3475 4300);
PAINT GREEN (-3475 4300);
DISPLAY INVISIBLE (-3475 4300);
FORCEPROP 1 LAST HDL_TAP TRUE
J 0
(-3150 4125);
DISPLAY 0.872340 (-3150 4125);
DISPLAY INVISIBLE (-3150 4125);
FORCEPROP 1 LAST PATH I194
J 0
(-3477 4250);
DISPLAY 0.872340 (-3477 4250);
PAINT GREEN (-3477 4250);
DISPLAY INVISIBLE (-3477 4250);
FORCEADD TAP..1
(-3475 4200);
FORCEPROP 3 LASTPIN (-3525 4200) SIG_NAME M_C_CPU1_SB_DQ<1>
J 0
(-3515 4210);
DISPLAY 0.659574 (-3515 4210);
PAINT MONO (-3515 4210);
DISPLAY INVISIBLE (-3515 4210);
FORCEPROP 1 LASTPIN (-3525 4200) BN 1
J 0
(-3537 4208);
DISPLAY 0.489362 (-3537 4208);
PAINT GREEN (-3537 4208);
FORCEPROP 2 LAST CDS_LIB mstr_standard
J 0
(-3475 4200);
DISPLAY 0.723404 (-3475 4200);
PAINT MONO (-3475 4200);
DISPLAY INVISIBLE (-3475 4200);
FORCEPROP 1 LAST BODY_TYPE PLUMBING
J 0
(-3475 4250);
DISPLAY 0.872340 (-3475 4250);
PAINT GREEN (-3475 4250);
DISPLAY INVISIBLE (-3475 4250);
FORCEPROP 1 LAST HDL_TAP TRUE
J 0
(-3150 4075);
DISPLAY 0.872340 (-3150 4075);
DISPLAY INVISIBLE (-3150 4075);
FORCEPROP 1 LAST PATH I195
J 0
(-3477 4200);
DISPLAY 0.872340 (-3477 4200);
PAINT GREEN (-3477 4200);
DISPLAY INVISIBLE (-3477 4200);
FORCEADD TAP..1
(-3475 4100);
FORCEPROP 3 LASTPIN (-3525 4100) SIG_NAME M_C_CPU1_SB_DQ<3>
J 0
(-3515 4110);
DISPLAY 0.659574 (-3515 4110);
PAINT MONO (-3515 4110);
DISPLAY INVISIBLE (-3515 4110);
FORCEPROP 1 LASTPIN (-3525 4100) BN 3
J 0
(-3537 4108);
DISPLAY 0.489362 (-3537 4108);
PAINT GREEN (-3537 4108);
FORCEPROP 2 LAST CDS_LIB mstr_standard
J 0
(-3475 4100);
DISPLAY 0.723404 (-3475 4100);
PAINT MONO (-3475 4100);
DISPLAY INVISIBLE (-3475 4100);
FORCEPROP 1 LAST BODY_TYPE PLUMBING
J 0
(-3475 4150);
DISPLAY 0.872340 (-3475 4150);
PAINT GREEN (-3475 4150);
DISPLAY INVISIBLE (-3475 4150);
FORCEPROP 1 LAST HDL_TAP TRUE
J 0
(-3150 3975);
DISPLAY 0.872340 (-3150 3975);
DISPLAY INVISIBLE (-3150 3975);
FORCEPROP 1 LAST PATH I196
J 0
(-3477 4100);
DISPLAY 0.872340 (-3477 4100);
PAINT GREEN (-3477 4100);
DISPLAY INVISIBLE (-3477 4100);
FORCEADD TAP..1
(-3475 4150);
FORCEPROP 3 LASTPIN (-3525 4150) SIG_NAME M_C_CPU1_SB_DQ<2>
J 0
(-3515 4160);
DISPLAY 0.659574 (-3515 4160);
PAINT MONO (-3515 4160);
DISPLAY INVISIBLE (-3515 4160);
FORCEPROP 1 LASTPIN (-3525 4150) BN 2
J 0
(-3537 4158);
DISPLAY 0.489362 (-3537 4158);
PAINT GREEN (-3537 4158);
FORCEPROP 2 LAST CDS_LIB mstr_standard
J 0
(-3475 4150);
DISPLAY 0.723404 (-3475 4150);
PAINT MONO (-3475 4150);
DISPLAY INVISIBLE (-3475 4150);
FORCEPROP 1 LAST BODY_TYPE PLUMBING
J 0
(-3475 4200);
DISPLAY 0.872340 (-3475 4200);
PAINT GREEN (-3475 4200);
DISPLAY INVISIBLE (-3475 4200);
FORCEPROP 1 LAST HDL_TAP TRUE
J 0
(-3150 4025);
DISPLAY 0.872340 (-3150 4025);
DISPLAY INVISIBLE (-3150 4025);
FORCEPROP 1 LAST PATH I197
J 0
(-3477 4150);
DISPLAY 0.872340 (-3477 4150);
PAINT GREEN (-3477 4150);
DISPLAY INVISIBLE (-3477 4150);
FORCEADD OFFPAGE..6
R 2
(-2875 2500);
FORCEPROP 2 LAST $XR0 100 
J 0
(-2661 2500);
DISPLAY 0.638298 (-2661 2500);
PAINT MONO (-2661 2500);
FORCEPROP 2 LAST CDS_LIB mstr_standard
J 2
(-2875 2500);
DISPLAY 0.723404 (-2875 2500);
PAINT MONO (-2875 2500);
DISPLAY INVISIBLE (-2875 2500);
FORCEPROP 1 LAST OFFPAGE TRUE
J 2
(-3200 2375);
DISPLAY 0.872340 (-3200 2375);
PAINT GREEN (-3200 2375);
DISPLAY INVISIBLE (-3200 2375);
FORCEPROP 1 LAST COMMENT_BODY TRUE
J 2
(-2975 2425);
DISPLAY 0.872340 (-2975 2425);
PAINT GREEN (-2975 2425);
DISPLAY INVISIBLE (-2975 2425);
FORCEPROP 2 LAST PATH I198
J 0
(-2650 2550);
DISPLAY 1.021277 (-2650 2550);
DISPLAY INVISIBLE (-2650 2550);
FORCEADD TAP..1
(-3475 3950);
FORCEPROP 3 LASTPIN (-3525 3950) SIG_NAME M_C_CPU1_SB_DQ<6>
J 0
(-3515 3960);
DISPLAY 0.659574 (-3515 3960);
PAINT MONO (-3515 3960);
DISPLAY INVISIBLE (-3515 3960);
FORCEPROP 1 LASTPIN (-3525 3950) BN 6
J 0
(-3537 3958);
DISPLAY 0.489362 (-3537 3958);
PAINT GREEN (-3537 3958);
FORCEPROP 2 LAST CDS_LIB mstr_standard
J 0
(-3475 3950);
DISPLAY 0.723404 (-3475 3950);
PAINT MONO (-3475 3950);
DISPLAY INVISIBLE (-3475 3950);
FORCEPROP 1 LAST BODY_TYPE PLUMBING
J 0
(-3475 4000);
DISPLAY 0.872340 (-3475 4000);
PAINT GREEN (-3475 4000);
DISPLAY INVISIBLE (-3475 4000);
FORCEPROP 1 LAST HDL_TAP TRUE
J 0
(-3150 3825);
DISPLAY 0.872340 (-3150 3825);
DISPLAY INVISIBLE (-3150 3825);
FORCEPROP 1 LAST PATH I199
J 0
(-3477 3950);
DISPLAY 0.872340 (-3477 3950);
PAINT GREEN (-3477 3950);
DISPLAY INVISIBLE (-3477 3950);
FORCEADD TAP..1
(-3475 4000);
FORCEPROP 3 LASTPIN (-3525 4000) SIG_NAME M_C_CPU1_SB_DQ<5>
J 0
(-3515 4010);
DISPLAY 0.659574 (-3515 4010);
PAINT MONO (-3515 4010);
DISPLAY INVISIBLE (-3515 4010);
FORCEPROP 1 LASTPIN (-3525 4000) BN 5
J 0
(-3537 4008);
DISPLAY 0.489362 (-3537 4008);
PAINT GREEN (-3537 4008);
FORCEPROP 2 LAST CDS_LIB mstr_standard
J 0
(-3475 4000);
DISPLAY 0.723404 (-3475 4000);
PAINT MONO (-3475 4000);
DISPLAY INVISIBLE (-3475 4000);
FORCEPROP 1 LAST BODY_TYPE PLUMBING
J 0
(-3475 4050);
DISPLAY 0.872340 (-3475 4050);
PAINT GREEN (-3475 4050);
DISPLAY INVISIBLE (-3475 4050);
FORCEPROP 1 LAST HDL_TAP TRUE
J 0
(-3150 3875);
DISPLAY 0.872340 (-3150 3875);
DISPLAY INVISIBLE (-3150 3875);
FORCEPROP 1 LAST PATH I200
J 0
(-3477 4000);
DISPLAY 0.872340 (-3477 4000);
PAINT GREEN (-3477 4000);
DISPLAY INVISIBLE (-3477 4000);
FORCEADD TAP..1
(-3475 4050);
FORCEPROP 3 LASTPIN (-3525 4050) SIG_NAME M_C_CPU1_SB_DQ<4>
J 0
(-3515 4060);
DISPLAY 0.659574 (-3515 4060);
PAINT MONO (-3515 4060);
DISPLAY INVISIBLE (-3515 4060);
FORCEPROP 1 LASTPIN (-3525 4050) BN 4
J 0
(-3537 4058);
DISPLAY 0.489362 (-3537 4058);
PAINT GREEN (-3537 4058);
FORCEPROP 2 LAST CDS_LIB mstr_standard
J 0
(-3475 4050);
DISPLAY 0.723404 (-3475 4050);
PAINT MONO (-3475 4050);
DISPLAY INVISIBLE (-3475 4050);
FORCEPROP 1 LAST BODY_TYPE PLUMBING
J 0
(-3475 4100);
DISPLAY 0.872340 (-3475 4100);
PAINT GREEN (-3475 4100);
DISPLAY INVISIBLE (-3475 4100);
FORCEPROP 1 LAST HDL_TAP TRUE
J 0
(-3150 3925);
DISPLAY 0.872340 (-3150 3925);
DISPLAY INVISIBLE (-3150 3925);
FORCEPROP 1 LAST PATH I201
J 0
(-3477 4050);
DISPLAY 0.872340 (-3477 4050);
PAINT GREEN (-3477 4050);
DISPLAY INVISIBLE (-3477 4050);
FORCEADD TAP..1
(-3475 3900);
FORCEPROP 3 LASTPIN (-3525 3900) SIG_NAME M_C_CPU1_SB_DQ<7>
J 0
(-3515 3910);
DISPLAY 0.659574 (-3515 3910);
PAINT MONO (-3515 3910);
DISPLAY INVISIBLE (-3515 3910);
FORCEPROP 1 LASTPIN (-3525 3900) BN 7
J 0
(-3537 3908);
DISPLAY 0.489362 (-3537 3908);
PAINT GREEN (-3537 3908);
FORCEPROP 2 LAST CDS_LIB mstr_standard
J 0
(-3475 3900);
DISPLAY 0.723404 (-3475 3900);
PAINT MONO (-3475 3900);
DISPLAY INVISIBLE (-3475 3900);
FORCEPROP 1 LAST BODY_TYPE PLUMBING
J 0
(-3475 3950);
DISPLAY 0.872340 (-3475 3950);
PAINT GREEN (-3475 3950);
DISPLAY INVISIBLE (-3475 3950);
FORCEPROP 1 LAST HDL_TAP TRUE
J 0
(-3150 3775);
DISPLAY 0.872340 (-3150 3775);
DISPLAY INVISIBLE (-3150 3775);
FORCEPROP 1 LAST PATH I202
J 0
(-3477 3900);
DISPLAY 0.872340 (-3477 3900);
PAINT GREEN (-3477 3900);
DISPLAY INVISIBLE (-3477 3900);
FORCEADD TAP..1
(-3475 3750);
FORCEPROP 3 LASTPIN (-3525 3750) SIG_NAME M_C_CPU1_SB_DQ<9>
J 0
(-3515 3760);
DISPLAY 0.659574 (-3515 3760);
PAINT MONO (-3515 3760);
DISPLAY INVISIBLE (-3515 3760);
FORCEPROP 1 LASTPIN (-3525 3750) BN 9
J 0
(-3537 3758);
DISPLAY 0.489362 (-3537 3758);
PAINT GREEN (-3537 3758);
FORCEPROP 2 LAST CDS_LIB mstr_standard
J 0
(-3475 3750);
DISPLAY 0.723404 (-3475 3750);
PAINT MONO (-3475 3750);
DISPLAY INVISIBLE (-3475 3750);
FORCEPROP 1 LAST BODY_TYPE PLUMBING
J 0
(-3475 3800);
DISPLAY 0.872340 (-3475 3800);
PAINT GREEN (-3475 3800);
DISPLAY INVISIBLE (-3475 3800);
FORCEPROP 1 LAST HDL_TAP TRUE
J 0
(-3150 3625);
DISPLAY 0.872340 (-3150 3625);
DISPLAY INVISIBLE (-3150 3625);
FORCEPROP 1 LAST PATH I203
J 0
(-3477 3750);
DISPLAY 0.872340 (-3477 3750);
PAINT GREEN (-3477 3750);
DISPLAY INVISIBLE (-3477 3750);
FORCEADD TAP..1
(-3475 3800);
FORCEPROP 3 LASTPIN (-3525 3800) SIG_NAME M_C_CPU1_SB_DQ<8>
J 0
(-3515 3810);
DISPLAY 0.659574 (-3515 3810);
PAINT MONO (-3515 3810);
DISPLAY INVISIBLE (-3515 3810);
FORCEPROP 1 LASTPIN (-3525 3800) BN 8
J 0
(-3537 3808);
DISPLAY 0.489362 (-3537 3808);
PAINT GREEN (-3537 3808);
FORCEPROP 2 LAST CDS_LIB mstr_standard
J 0
(-3475 3800);
DISPLAY 0.723404 (-3475 3800);
PAINT MONO (-3475 3800);
DISPLAY INVISIBLE (-3475 3800);
FORCEPROP 1 LAST BODY_TYPE PLUMBING
J 0
(-3475 3850);
DISPLAY 0.872340 (-3475 3850);
PAINT GREEN (-3475 3850);
DISPLAY INVISIBLE (-3475 3850);
FORCEPROP 1 LAST HDL_TAP TRUE
J 0
(-3150 3675);
DISPLAY 0.872340 (-3150 3675);
DISPLAY INVISIBLE (-3150 3675);
FORCEPROP 1 LAST PATH I204
J 0
(-3477 3800);
DISPLAY 0.872340 (-3477 3800);
PAINT GREEN (-3477 3800);
DISPLAY INVISIBLE (-3477 3800);
FORCEADD TAP..1
(-3475 3700);
FORCEPROP 3 LASTPIN (-3525 3700) SIG_NAME M_C_CPU1_SB_DQ<10>
J 0
(-3515 3710);
DISPLAY 0.659574 (-3515 3710);
PAINT MONO (-3515 3710);
DISPLAY INVISIBLE (-3515 3710);
FORCEPROP 1 LASTPIN (-3525 3700) BN 10
J 0
(-3537 3708);
DISPLAY 0.489362 (-3537 3708);
PAINT GREEN (-3537 3708);
FORCEPROP 2 LAST CDS_LIB mstr_standard
J 0
(-3475 3700);
DISPLAY 0.723404 (-3475 3700);
PAINT MONO (-3475 3700);
DISPLAY INVISIBLE (-3475 3700);
FORCEPROP 1 LAST BODY_TYPE PLUMBING
J 0
(-3475 3750);
DISPLAY 0.872340 (-3475 3750);
PAINT GREEN (-3475 3750);
DISPLAY INVISIBLE (-3475 3750);
FORCEPROP 1 LAST HDL_TAP TRUE
J 0
(-3150 3575);
DISPLAY 0.872340 (-3150 3575);
DISPLAY INVISIBLE (-3150 3575);
FORCEPROP 1 LAST PATH I205
J 0
(-3477 3700);
DISPLAY 0.872340 (-3477 3700);
PAINT GREEN (-3477 3700);
DISPLAY INVISIBLE (-3477 3700);
FORCEADD TAP..1
(-3475 3600);
FORCEPROP 3 LASTPIN (-3525 3600) SIG_NAME M_C_CPU1_SB_DQ<12>
J 0
(-3515 3610);
DISPLAY 0.659574 (-3515 3610);
PAINT MONO (-3515 3610);
DISPLAY INVISIBLE (-3515 3610);
FORCEPROP 1 LASTPIN (-3525 3600) BN 12
J 0
(-3537 3608);
DISPLAY 0.489362 (-3537 3608);
PAINT GREEN (-3537 3608);
FORCEPROP 2 LAST CDS_LIB mstr_standard
J 0
(-3475 3600);
DISPLAY 0.723404 (-3475 3600);
PAINT MONO (-3475 3600);
DISPLAY INVISIBLE (-3475 3600);
FORCEPROP 1 LAST BODY_TYPE PLUMBING
J 0
(-3475 3650);
DISPLAY 0.872340 (-3475 3650);
PAINT GREEN (-3475 3650);
DISPLAY INVISIBLE (-3475 3650);
FORCEPROP 1 LAST HDL_TAP TRUE
J 0
(-3150 3475);
DISPLAY 0.872340 (-3150 3475);
DISPLAY INVISIBLE (-3150 3475);
FORCEPROP 1 LAST PATH I206
J 0
(-3477 3600);
DISPLAY 0.872340 (-3477 3600);
PAINT GREEN (-3477 3600);
DISPLAY INVISIBLE (-3477 3600);
FORCEADD TAP..1
(-3475 3650);
FORCEPROP 3 LASTPIN (-3525 3650) SIG_NAME M_C_CPU1_SB_DQ<11>
J 0
(-3515 3660);
DISPLAY 0.659574 (-3515 3660);
PAINT MONO (-3515 3660);
DISPLAY INVISIBLE (-3515 3660);
FORCEPROP 1 LASTPIN (-3525 3650) BN 11
J 0
(-3537 3658);
DISPLAY 0.489362 (-3537 3658);
PAINT GREEN (-3537 3658);
FORCEPROP 2 LAST CDS_LIB mstr_standard
J 0
(-3475 3650);
DISPLAY 0.723404 (-3475 3650);
PAINT MONO (-3475 3650);
DISPLAY INVISIBLE (-3475 3650);
FORCEPROP 1 LAST BODY_TYPE PLUMBING
J 0
(-3475 3700);
DISPLAY 0.872340 (-3475 3700);
PAINT GREEN (-3475 3700);
DISPLAY INVISIBLE (-3475 3700);
FORCEPROP 1 LAST HDL_TAP TRUE
J 0
(-3150 3525);
DISPLAY 0.872340 (-3150 3525);
DISPLAY INVISIBLE (-3150 3525);
FORCEPROP 1 LAST PATH I207
J 0
(-3477 3650);
DISPLAY 0.872340 (-3477 3650);
PAINT GREEN (-3477 3650);
DISPLAY INVISIBLE (-3477 3650);
FORCEADD TAP..1
(-3475 3550);
FORCEPROP 3 LASTPIN (-3525 3550) SIG_NAME M_C_CPU1_SB_DQ<13>
J 0
(-3515 3560);
DISPLAY 0.659574 (-3515 3560);
PAINT MONO (-3515 3560);
DISPLAY INVISIBLE (-3515 3560);
FORCEPROP 1 LASTPIN (-3525 3550) BN 13
J 0
(-3537 3558);
DISPLAY 0.489362 (-3537 3558);
PAINT GREEN (-3537 3558);
FORCEPROP 2 LAST CDS_LIB mstr_standard
J 0
(-3475 3550);
DISPLAY 0.723404 (-3475 3550);
PAINT MONO (-3475 3550);
DISPLAY INVISIBLE (-3475 3550);
FORCEPROP 1 LAST BODY_TYPE PLUMBING
J 0
(-3475 3600);
DISPLAY 0.872340 (-3475 3600);
PAINT GREEN (-3475 3600);
DISPLAY INVISIBLE (-3475 3600);
FORCEPROP 1 LAST HDL_TAP TRUE
J 0
(-3150 3425);
DISPLAY 0.872340 (-3150 3425);
DISPLAY INVISIBLE (-3150 3425);
FORCEPROP 1 LAST PATH I208
J 0
(-3477 3550);
DISPLAY 0.872340 (-3477 3550);
PAINT GREEN (-3477 3550);
DISPLAY INVISIBLE (-3477 3550);
FORCEADD TAP..1
(-3475 3450);
FORCEPROP 3 LASTPIN (-3525 3450) SIG_NAME M_C_CPU1_SB_DQ<15>
J 0
(-3515 3460);
DISPLAY 0.659574 (-3515 3460);
PAINT MONO (-3515 3460);
DISPLAY INVISIBLE (-3515 3460);
FORCEPROP 1 LASTPIN (-3525 3450) BN 15
J 0
(-3537 3458);
DISPLAY 0.489362 (-3537 3458);
PAINT GREEN (-3537 3458);
FORCEPROP 2 LAST CDS_LIB mstr_standard
J 0
(-3475 3450);
DISPLAY 0.723404 (-3475 3450);
PAINT MONO (-3475 3450);
DISPLAY INVISIBLE (-3475 3450);
FORCEPROP 1 LAST BODY_TYPE PLUMBING
J 0
(-3475 3500);
DISPLAY 0.872340 (-3475 3500);
PAINT GREEN (-3475 3500);
DISPLAY INVISIBLE (-3475 3500);
FORCEPROP 1 LAST HDL_TAP TRUE
J 0
(-3150 3325);
DISPLAY 0.872340 (-3150 3325);
DISPLAY INVISIBLE (-3150 3325);
FORCEPROP 1 LAST PATH I209
J 0
(-3477 3450);
DISPLAY 0.872340 (-3477 3450);
PAINT GREEN (-3477 3450);
DISPLAY INVISIBLE (-3477 3450);
FORCEADD TAP..1
(-3475 3500);
FORCEPROP 3 LASTPIN (-3525 3500) SIG_NAME M_C_CPU1_SB_DQ<14>
J 0
(-3515 3510);
DISPLAY 0.659574 (-3515 3510);
PAINT MONO (-3515 3510);
DISPLAY INVISIBLE (-3515 3510);
FORCEPROP 1 LASTPIN (-3525 3500) BN 14
J 0
(-3537 3508);
DISPLAY 0.489362 (-3537 3508);
PAINT GREEN (-3537 3508);
FORCEPROP 2 LAST CDS_LIB mstr_standard
J 0
(-3475 3500);
DISPLAY 0.723404 (-3475 3500);
PAINT MONO (-3475 3500);
DISPLAY INVISIBLE (-3475 3500);
FORCEPROP 1 LAST BODY_TYPE PLUMBING
J 0
(-3475 3550);
DISPLAY 0.872340 (-3475 3550);
PAINT GREEN (-3475 3550);
DISPLAY INVISIBLE (-3475 3550);
FORCEPROP 1 LAST HDL_TAP TRUE
J 0
(-3150 3375);
DISPLAY 0.872340 (-3150 3375);
DISPLAY INVISIBLE (-3150 3375);
FORCEPROP 1 LAST PATH I210
J 0
(-3477 3500);
DISPLAY 0.872340 (-3477 3500);
PAINT GREEN (-3477 3500);
DISPLAY INVISIBLE (-3477 3500);
FORCEADD TAP..1
(-3475 3350);
FORCEPROP 3 LASTPIN (-3525 3350) SIG_NAME M_C_CPU1_SB_DQ<16>
J 0
(-3515 3360);
DISPLAY 0.659574 (-3515 3360);
PAINT MONO (-3515 3360);
DISPLAY INVISIBLE (-3515 3360);
FORCEPROP 1 LASTPIN (-3525 3350) BN 16
J 0
(-3537 3358);
DISPLAY 0.489362 (-3537 3358);
PAINT GREEN (-3537 3358);
FORCEPROP 2 LAST CDS_LIB mstr_standard
J 0
(-3475 3350);
DISPLAY 0.723404 (-3475 3350);
PAINT MONO (-3475 3350);
DISPLAY INVISIBLE (-3475 3350);
FORCEPROP 1 LAST BODY_TYPE PLUMBING
J 0
(-3475 3400);
DISPLAY 0.872340 (-3475 3400);
PAINT GREEN (-3475 3400);
DISPLAY INVISIBLE (-3475 3400);
FORCEPROP 1 LAST HDL_TAP TRUE
J 0
(-3150 3225);
DISPLAY 0.872340 (-3150 3225);
DISPLAY INVISIBLE (-3150 3225);
FORCEPROP 1 LAST PATH I211
J 0
(-3477 3350);
DISPLAY 0.872340 (-3477 3350);
PAINT GREEN (-3477 3350);
DISPLAY INVISIBLE (-3477 3350);
FORCEADD TAP..1
(-3475 3250);
FORCEPROP 3 LASTPIN (-3525 3250) SIG_NAME M_C_CPU1_SB_DQ<18>
J 0
(-3515 3260);
DISPLAY 0.659574 (-3515 3260);
PAINT MONO (-3515 3260);
DISPLAY INVISIBLE (-3515 3260);
FORCEPROP 1 LASTPIN (-3525 3250) BN 18
J 0
(-3537 3258);
DISPLAY 0.489362 (-3537 3258);
PAINT GREEN (-3537 3258);
FORCEPROP 2 LAST CDS_LIB mstr_standard
J 0
(-3475 3250);
DISPLAY 0.723404 (-3475 3250);
PAINT MONO (-3475 3250);
DISPLAY INVISIBLE (-3475 3250);
FORCEPROP 1 LAST BODY_TYPE PLUMBING
J 0
(-3475 3300);
DISPLAY 0.872340 (-3475 3300);
PAINT GREEN (-3475 3300);
DISPLAY INVISIBLE (-3475 3300);
FORCEPROP 1 LAST HDL_TAP TRUE
J 0
(-3150 3125);
DISPLAY 0.872340 (-3150 3125);
DISPLAY INVISIBLE (-3150 3125);
FORCEPROP 1 LAST PATH I212
J 0
(-3477 3250);
DISPLAY 0.872340 (-3477 3250);
PAINT GREEN (-3477 3250);
DISPLAY INVISIBLE (-3477 3250);
FORCEADD TAP..1
(-3475 3300);
FORCEPROP 3 LASTPIN (-3525 3300) SIG_NAME M_C_CPU1_SB_DQ<17>
J 0
(-3515 3310);
DISPLAY 0.659574 (-3515 3310);
PAINT MONO (-3515 3310);
DISPLAY INVISIBLE (-3515 3310);
FORCEPROP 1 LASTPIN (-3525 3300) BN 17
J 0
(-3537 3308);
DISPLAY 0.489362 (-3537 3308);
PAINT GREEN (-3537 3308);
FORCEPROP 2 LAST CDS_LIB mstr_standard
J 0
(-3475 3300);
DISPLAY 0.723404 (-3475 3300);
PAINT MONO (-3475 3300);
DISPLAY INVISIBLE (-3475 3300);
FORCEPROP 1 LAST BODY_TYPE PLUMBING
J 0
(-3475 3350);
DISPLAY 0.872340 (-3475 3350);
PAINT GREEN (-3475 3350);
DISPLAY INVISIBLE (-3475 3350);
FORCEPROP 1 LAST HDL_TAP TRUE
J 0
(-3150 3175);
DISPLAY 0.872340 (-3150 3175);
DISPLAY INVISIBLE (-3150 3175);
FORCEPROP 1 LAST PATH I213
J 0
(-3477 3300);
DISPLAY 0.872340 (-3477 3300);
PAINT GREEN (-3477 3300);
DISPLAY INVISIBLE (-3477 3300);
FORCEADD TAP..1
(-3475 3200);
FORCEPROP 3 LASTPIN (-3525 3200) SIG_NAME M_C_CPU1_SB_DQ<19>
J 0
(-3515 3210);
DISPLAY 0.659574 (-3515 3210);
PAINT MONO (-3515 3210);
DISPLAY INVISIBLE (-3515 3210);
FORCEPROP 1 LASTPIN (-3525 3200) BN 19
J 0
(-3537 3208);
DISPLAY 0.489362 (-3537 3208);
PAINT GREEN (-3537 3208);
FORCEPROP 2 LAST CDS_LIB mstr_standard
J 0
(-3475 3200);
DISPLAY 0.723404 (-3475 3200);
PAINT MONO (-3475 3200);
DISPLAY INVISIBLE (-3475 3200);
FORCEPROP 1 LAST BODY_TYPE PLUMBING
J 0
(-3475 3250);
DISPLAY 0.872340 (-3475 3250);
PAINT GREEN (-3475 3250);
DISPLAY INVISIBLE (-3475 3250);
FORCEPROP 1 LAST HDL_TAP TRUE
J 0
(-3150 3075);
DISPLAY 0.872340 (-3150 3075);
DISPLAY INVISIBLE (-3150 3075);
FORCEPROP 1 LAST PATH I214
J 0
(-3477 3200);
DISPLAY 0.872340 (-3477 3200);
PAINT GREEN (-3477 3200);
DISPLAY INVISIBLE (-3477 3200);
FORCEADD TAP..1
(-3475 3100);
FORCEPROP 3 LASTPIN (-3525 3100) SIG_NAME M_C_CPU1_SB_DQ<21>
J 0
(-3515 3110);
DISPLAY 0.659574 (-3515 3110);
PAINT MONO (-3515 3110);
DISPLAY INVISIBLE (-3515 3110);
FORCEPROP 1 LASTPIN (-3525 3100) BN 21
J 0
(-3537 3108);
DISPLAY 0.489362 (-3537 3108);
PAINT GREEN (-3537 3108);
FORCEPROP 2 LAST CDS_LIB mstr_standard
J 0
(-3475 3100);
DISPLAY 0.723404 (-3475 3100);
PAINT MONO (-3475 3100);
DISPLAY INVISIBLE (-3475 3100);
FORCEPROP 1 LAST BODY_TYPE PLUMBING
J 0
(-3475 3150);
DISPLAY 0.872340 (-3475 3150);
PAINT GREEN (-3475 3150);
DISPLAY INVISIBLE (-3475 3150);
FORCEPROP 1 LAST HDL_TAP TRUE
J 0
(-3150 2975);
DISPLAY 0.872340 (-3150 2975);
DISPLAY INVISIBLE (-3150 2975);
FORCEPROP 1 LAST PATH I215
J 0
(-3477 3100);
DISPLAY 0.872340 (-3477 3100);
PAINT GREEN (-3477 3100);
DISPLAY INVISIBLE (-3477 3100);
FORCEADD TAP..1
(-3475 3150);
FORCEPROP 3 LASTPIN (-3525 3150) SIG_NAME M_C_CPU1_SB_DQ<20>
J 0
(-3515 3160);
DISPLAY 0.659574 (-3515 3160);
PAINT MONO (-3515 3160);
DISPLAY INVISIBLE (-3515 3160);
FORCEPROP 1 LASTPIN (-3525 3150) BN 20
J 0
(-3537 3158);
DISPLAY 0.489362 (-3537 3158);
PAINT GREEN (-3537 3158);
FORCEPROP 2 LAST CDS_LIB mstr_standard
J 0
(-3475 3150);
DISPLAY 0.723404 (-3475 3150);
PAINT MONO (-3475 3150);
DISPLAY INVISIBLE (-3475 3150);
FORCEPROP 1 LAST BODY_TYPE PLUMBING
J 0
(-3475 3200);
DISPLAY 0.872340 (-3475 3200);
PAINT GREEN (-3475 3200);
DISPLAY INVISIBLE (-3475 3200);
FORCEPROP 1 LAST HDL_TAP TRUE
J 0
(-3150 3025);
DISPLAY 0.872340 (-3150 3025);
DISPLAY INVISIBLE (-3150 3025);
FORCEPROP 1 LAST PATH I216
J 0
(-3477 3150);
DISPLAY 0.872340 (-3477 3150);
PAINT GREEN (-3477 3150);
DISPLAY INVISIBLE (-3477 3150);
FORCEADD TAP..1
(-3475 3050);
FORCEPROP 3 LASTPIN (-3525 3050) SIG_NAME M_C_CPU1_SB_DQ<22>
J 0
(-3515 3060);
DISPLAY 0.659574 (-3515 3060);
PAINT MONO (-3515 3060);
DISPLAY INVISIBLE (-3515 3060);
FORCEPROP 1 LASTPIN (-3525 3050) BN 22
J 0
(-3537 3058);
DISPLAY 0.489362 (-3537 3058);
PAINT GREEN (-3537 3058);
FORCEPROP 2 LAST CDS_LIB mstr_standard
J 0
(-3475 3050);
DISPLAY 0.723404 (-3475 3050);
PAINT MONO (-3475 3050);
DISPLAY INVISIBLE (-3475 3050);
FORCEPROP 1 LAST BODY_TYPE PLUMBING
J 0
(-3475 3100);
DISPLAY 0.872340 (-3475 3100);
PAINT GREEN (-3475 3100);
DISPLAY INVISIBLE (-3475 3100);
FORCEPROP 1 LAST HDL_TAP TRUE
J 0
(-3150 2925);
DISPLAY 0.872340 (-3150 2925);
DISPLAY INVISIBLE (-3150 2925);
FORCEPROP 1 LAST PATH I217
J 0
(-3477 3050);
DISPLAY 0.872340 (-3477 3050);
PAINT GREEN (-3477 3050);
DISPLAY INVISIBLE (-3477 3050);
FORCEADD TAP..1
(-3475 2900);
FORCEPROP 3 LASTPIN (-3525 2900) SIG_NAME M_C_CPU1_SB_DQ<24>
J 0
(-3515 2910);
DISPLAY 0.659574 (-3515 2910);
PAINT MONO (-3515 2910);
DISPLAY INVISIBLE (-3515 2910);
FORCEPROP 1 LASTPIN (-3525 2900) BN 24
J 0
(-3537 2908);
DISPLAY 0.489362 (-3537 2908);
PAINT GREEN (-3537 2908);
FORCEPROP 2 LAST CDS_LIB mstr_standard
J 0
(-3475 2900);
DISPLAY 0.723404 (-3475 2900);
PAINT MONO (-3475 2900);
DISPLAY INVISIBLE (-3475 2900);
FORCEPROP 1 LAST BODY_TYPE PLUMBING
J 0
(-3475 2950);
DISPLAY 0.872340 (-3475 2950);
PAINT GREEN (-3475 2950);
DISPLAY INVISIBLE (-3475 2950);
FORCEPROP 1 LAST HDL_TAP TRUE
J 0
(-3150 2775);
DISPLAY 0.872340 (-3150 2775);
DISPLAY INVISIBLE (-3150 2775);
FORCEPROP 1 LAST PATH I218
J 0
(-3477 2900);
DISPLAY 0.872340 (-3477 2900);
PAINT GREEN (-3477 2900);
DISPLAY INVISIBLE (-3477 2900);
FORCEADD TAP..1
(-3475 2850);
FORCEPROP 3 LASTPIN (-3525 2850) SIG_NAME M_C_CPU1_SB_DQ<25>
J 0
(-3515 2860);
DISPLAY 0.659574 (-3515 2860);
PAINT MONO (-3515 2860);
DISPLAY INVISIBLE (-3515 2860);
FORCEPROP 1 LASTPIN (-3525 2850) BN 25
J 0
(-3537 2858);
DISPLAY 0.489362 (-3537 2858);
PAINT GREEN (-3537 2858);
FORCEPROP 2 LAST CDS_LIB mstr_standard
J 0
(-3475 2850);
DISPLAY 0.723404 (-3475 2850);
PAINT MONO (-3475 2850);
DISPLAY INVISIBLE (-3475 2850);
FORCEPROP 1 LAST BODY_TYPE PLUMBING
J 0
(-3475 2900);
DISPLAY 0.872340 (-3475 2900);
PAINT GREEN (-3475 2900);
DISPLAY INVISIBLE (-3475 2900);
FORCEPROP 1 LAST HDL_TAP TRUE
J 0
(-3150 2725);
DISPLAY 0.872340 (-3150 2725);
DISPLAY INVISIBLE (-3150 2725);
FORCEPROP 1 LAST PATH I219
J 0
(-3477 2850);
DISPLAY 0.872340 (-3477 2850);
PAINT GREEN (-3477 2850);
DISPLAY INVISIBLE (-3477 2850);
FORCEADD TAP..1
(-3475 3000);
FORCEPROP 3 LASTPIN (-3525 3000) SIG_NAME M_C_CPU1_SB_DQ<23>
J 0
(-3515 3010);
DISPLAY 0.659574 (-3515 3010);
PAINT MONO (-3515 3010);
DISPLAY INVISIBLE (-3515 3010);
FORCEPROP 1 LASTPIN (-3525 3000) BN 23
J 0
(-3537 3008);
DISPLAY 0.489362 (-3537 3008);
PAINT GREEN (-3537 3008);
FORCEPROP 2 LAST CDS_LIB mstr_standard
J 0
(-3475 3000);
DISPLAY 0.723404 (-3475 3000);
PAINT MONO (-3475 3000);
DISPLAY INVISIBLE (-3475 3000);
FORCEPROP 1 LAST BODY_TYPE PLUMBING
J 0
(-3475 3050);
DISPLAY 0.872340 (-3475 3050);
PAINT GREEN (-3475 3050);
DISPLAY INVISIBLE (-3475 3050);
FORCEPROP 1 LAST HDL_TAP TRUE
J 0
(-3150 2875);
DISPLAY 0.872340 (-3150 2875);
DISPLAY INVISIBLE (-3150 2875);
FORCEPROP 1 LAST PATH I220
J 0
(-3477 3000);
DISPLAY 0.872340 (-3477 3000);
PAINT GREEN (-3477 3000);
DISPLAY INVISIBLE (-3477 3000);
FORCEADD TAP..1
(-3475 2750);
FORCEPROP 3 LASTPIN (-3525 2750) SIG_NAME M_C_CPU1_SB_DQ<27>
J 0
(-3515 2760);
DISPLAY 0.659574 (-3515 2760);
PAINT MONO (-3515 2760);
DISPLAY INVISIBLE (-3515 2760);
FORCEPROP 1 LASTPIN (-3525 2750) BN 27
J 0
(-3537 2758);
DISPLAY 0.489362 (-3537 2758);
PAINT GREEN (-3537 2758);
FORCEPROP 2 LAST CDS_LIB mstr_standard
J 0
(-3475 2750);
DISPLAY 0.723404 (-3475 2750);
PAINT MONO (-3475 2750);
DISPLAY INVISIBLE (-3475 2750);
FORCEPROP 1 LAST BODY_TYPE PLUMBING
J 0
(-3475 2800);
DISPLAY 0.872340 (-3475 2800);
PAINT GREEN (-3475 2800);
DISPLAY INVISIBLE (-3475 2800);
FORCEPROP 1 LAST HDL_TAP TRUE
J 0
(-3150 2625);
DISPLAY 0.872340 (-3150 2625);
DISPLAY INVISIBLE (-3150 2625);
FORCEPROP 1 LAST PATH I221
J 0
(-3477 2750);
DISPLAY 0.872340 (-3477 2750);
PAINT GREEN (-3477 2750);
DISPLAY INVISIBLE (-3477 2750);
FORCEADD TAP..1
(-3475 2700);
FORCEPROP 3 LASTPIN (-3525 2700) SIG_NAME M_C_CPU1_SB_DQ<28>
J 0
(-3515 2710);
DISPLAY 0.659574 (-3515 2710);
PAINT MONO (-3515 2710);
DISPLAY INVISIBLE (-3515 2710);
FORCEPROP 1 LASTPIN (-3525 2700) BN 28
J 0
(-3537 2708);
DISPLAY 0.489362 (-3537 2708);
PAINT GREEN (-3537 2708);
FORCEPROP 2 LAST CDS_LIB mstr_standard
J 0
(-3475 2700);
DISPLAY 0.723404 (-3475 2700);
PAINT MONO (-3475 2700);
DISPLAY INVISIBLE (-3475 2700);
FORCEPROP 1 LAST BODY_TYPE PLUMBING
J 0
(-3475 2750);
DISPLAY 0.872340 (-3475 2750);
PAINT GREEN (-3475 2750);
DISPLAY INVISIBLE (-3475 2750);
FORCEPROP 1 LAST HDL_TAP TRUE
J 0
(-3150 2575);
DISPLAY 0.872340 (-3150 2575);
DISPLAY INVISIBLE (-3150 2575);
FORCEPROP 1 LAST PATH I222
J 0
(-3477 2700);
DISPLAY 0.872340 (-3477 2700);
PAINT GREEN (-3477 2700);
DISPLAY INVISIBLE (-3477 2700);
FORCEADD TAP..1
(-3475 2800);
FORCEPROP 3 LASTPIN (-3525 2800) SIG_NAME M_C_CPU1_SB_DQ<26>
J 0
(-3515 2810);
DISPLAY 0.659574 (-3515 2810);
PAINT MONO (-3515 2810);
DISPLAY INVISIBLE (-3515 2810);
FORCEPROP 1 LASTPIN (-3525 2800) BN 26
J 0
(-3537 2808);
DISPLAY 0.489362 (-3537 2808);
PAINT GREEN (-3537 2808);
FORCEPROP 2 LAST CDS_LIB mstr_standard
J 0
(-3475 2800);
DISPLAY 0.723404 (-3475 2800);
PAINT MONO (-3475 2800);
DISPLAY INVISIBLE (-3475 2800);
FORCEPROP 1 LAST BODY_TYPE PLUMBING
J 0
(-3475 2850);
DISPLAY 0.872340 (-3475 2850);
PAINT GREEN (-3475 2850);
DISPLAY INVISIBLE (-3475 2850);
FORCEPROP 1 LAST HDL_TAP TRUE
J 0
(-3150 2675);
DISPLAY 0.872340 (-3150 2675);
DISPLAY INVISIBLE (-3150 2675);
FORCEPROP 1 LAST PATH I223
J 0
(-3477 2800);
DISPLAY 0.872340 (-3477 2800);
PAINT GREEN (-3477 2800);
DISPLAY INVISIBLE (-3477 2800);
FORCEADD TAP..1
(-3475 2650);
FORCEPROP 3 LASTPIN (-3525 2650) SIG_NAME M_C_CPU1_SB_DQ<29>
J 0
(-3515 2660);
DISPLAY 0.659574 (-3515 2660);
PAINT MONO (-3515 2660);
DISPLAY INVISIBLE (-3515 2660);
FORCEPROP 1 LASTPIN (-3525 2650) BN 29
J 0
(-3537 2658);
DISPLAY 0.489362 (-3537 2658);
PAINT GREEN (-3537 2658);
FORCEPROP 2 LAST CDS_LIB mstr_standard
J 0
(-3475 2650);
DISPLAY 0.723404 (-3475 2650);
PAINT MONO (-3475 2650);
DISPLAY INVISIBLE (-3475 2650);
FORCEPROP 1 LAST BODY_TYPE PLUMBING
J 0
(-3475 2700);
DISPLAY 0.872340 (-3475 2700);
PAINT GREEN (-3475 2700);
DISPLAY INVISIBLE (-3475 2700);
FORCEPROP 1 LAST HDL_TAP TRUE
J 0
(-3150 2525);
DISPLAY 0.872340 (-3150 2525);
DISPLAY INVISIBLE (-3150 2525);
FORCEPROP 1 LAST PATH I224
J 0
(-3477 2650);
DISPLAY 0.872340 (-3477 2650);
PAINT GREEN (-3477 2650);
DISPLAY INVISIBLE (-3477 2650);
FORCEADD TAP..1
(-3475 2600);
FORCEPROP 3 LASTPIN (-3525 2600) SIG_NAME M_C_CPU1_SB_DQ<30>
J 0
(-3515 2610);
DISPLAY 0.659574 (-3515 2610);
PAINT MONO (-3515 2610);
DISPLAY INVISIBLE (-3515 2610);
FORCEPROP 1 LASTPIN (-3525 2600) BN 30
J 0
(-3537 2608);
DISPLAY 0.489362 (-3537 2608);
PAINT GREEN (-3537 2608);
FORCEPROP 2 LAST CDS_LIB mstr_standard
J 0
(-3475 2600);
DISPLAY 0.723404 (-3475 2600);
PAINT MONO (-3475 2600);
DISPLAY INVISIBLE (-3475 2600);
FORCEPROP 1 LAST BODY_TYPE PLUMBING
J 0
(-3475 2650);
DISPLAY 0.872340 (-3475 2650);
PAINT GREEN (-3475 2650);
DISPLAY INVISIBLE (-3475 2650);
FORCEPROP 1 LAST HDL_TAP TRUE
J 0
(-3150 2475);
DISPLAY 0.872340 (-3150 2475);
DISPLAY INVISIBLE (-3150 2475);
FORCEPROP 1 LAST PATH I225
J 0
(-3477 2600);
DISPLAY 0.872340 (-3477 2600);
PAINT GREEN (-3477 2600);
DISPLAY INVISIBLE (-3477 2600);
FORCEADD TAP..1
(-3475 2400);
FORCEPROP 3 LASTPIN (-3525 2400) SIG_NAME M_C_CPU1_SA_CB<1>
J 0
(-3515 2410);
DISPLAY 0.659574 (-3515 2410);
PAINT MONO (-3515 2410);
DISPLAY INVISIBLE (-3515 2410);
FORCEPROP 1 LASTPIN (-3525 2400) BN 1
J 0
(-3537 2408);
DISPLAY 0.489362 (-3537 2408);
PAINT GREEN (-3537 2408);
FORCEPROP 2 LAST CDS_LIB mstr_standard
J 2
(-3475 2400);
DISPLAY 0.723404 (-3475 2400);
PAINT MONO (-3475 2400);
DISPLAY INVISIBLE (-3475 2400);
FORCEPROP 1 LAST BODY_TYPE PLUMBING
J 0
(-3475 2450);
DISPLAY 0.872340 (-3475 2450);
PAINT GREEN (-3475 2450);
DISPLAY INVISIBLE (-3475 2450);
FORCEPROP 1 LAST HDL_TAP TRUE
J 0
(-3150 2275);
DISPLAY 0.872340 (-3150 2275);
DISPLAY INVISIBLE (-3150 2275);
FORCEPROP 1 LAST PATH I226
J 0
(-3477 2400);
DISPLAY 0.872340 (-3477 2400);
PAINT GREEN (-3477 2400);
DISPLAY INVISIBLE (-3477 2400);
FORCEADD TAP..1
(-3475 2350);
FORCEPROP 3 LASTPIN (-3525 2350) SIG_NAME M_C_CPU1_SA_CB<2>
J 0
(-3515 2360);
DISPLAY 0.659574 (-3515 2360);
PAINT MONO (-3515 2360);
DISPLAY INVISIBLE (-3515 2360);
FORCEPROP 1 LASTPIN (-3525 2350) BN 2
J 0
(-3537 2358);
DISPLAY 0.489362 (-3537 2358);
PAINT GREEN (-3537 2358);
FORCEPROP 2 LAST CDS_LIB mstr_standard
J 2
(-3475 2350);
DISPLAY 0.723404 (-3475 2350);
PAINT MONO (-3475 2350);
DISPLAY INVISIBLE (-3475 2350);
FORCEPROP 1 LAST BODY_TYPE PLUMBING
J 0
(-3475 2400);
DISPLAY 0.872340 (-3475 2400);
PAINT GREEN (-3475 2400);
DISPLAY INVISIBLE (-3475 2400);
FORCEPROP 1 LAST HDL_TAP TRUE
J 0
(-3150 2225);
DISPLAY 0.872340 (-3150 2225);
DISPLAY INVISIBLE (-3150 2225);
FORCEPROP 1 LAST PATH I227
J 0
(-3477 2350);
DISPLAY 0.872340 (-3477 2350);
PAINT GREEN (-3477 2350);
DISPLAY INVISIBLE (-3477 2350);
FORCEADD TAP..1
(-3475 2550);
FORCEPROP 3 LASTPIN (-3525 2550) SIG_NAME M_C_CPU1_SB_DQ<31>
J 0
(-3515 2560);
DISPLAY 0.659574 (-3515 2560);
PAINT MONO (-3515 2560);
DISPLAY INVISIBLE (-3515 2560);
FORCEPROP 1 LASTPIN (-3525 2550) BN 31
J 0
(-3537 2558);
DISPLAY 0.489362 (-3537 2558);
PAINT GREEN (-3537 2558);
FORCEPROP 2 LAST CDS_LIB mstr_standard
J 0
(-3475 2550);
DISPLAY 0.723404 (-3475 2550);
PAINT MONO (-3475 2550);
DISPLAY INVISIBLE (-3475 2550);
FORCEPROP 1 LAST BODY_TYPE PLUMBING
J 0
(-3475 2600);
DISPLAY 0.872340 (-3475 2600);
PAINT GREEN (-3475 2600);
DISPLAY INVISIBLE (-3475 2600);
FORCEPROP 1 LAST HDL_TAP TRUE
J 0
(-3150 2425);
DISPLAY 0.872340 (-3150 2425);
DISPLAY INVISIBLE (-3150 2425);
FORCEPROP 1 LAST PATH I228
J 0
(-3477 2550);
DISPLAY 0.872340 (-3477 2550);
PAINT GREEN (-3477 2550);
DISPLAY INVISIBLE (-3477 2550);
FORCEADD TAP..1
(-3475 2450);
FORCEPROP 3 LASTPIN (-3525 2450) SIG_NAME M_C_CPU1_SA_CB<0>
J 0
(-3515 2460);
DISPLAY 0.659574 (-3515 2460);
PAINT MONO (-3515 2460);
DISPLAY INVISIBLE (-3515 2460);
FORCEPROP 1 LASTPIN (-3525 2450) BN 0
J 0
(-3537 2458);
DISPLAY 0.489362 (-3537 2458);
PAINT GREEN (-3537 2458);
FORCEPROP 2 LAST CDS_LIB mstr_standard
J 2
(-3475 2450);
DISPLAY 0.723404 (-3475 2450);
PAINT MONO (-3475 2450);
DISPLAY INVISIBLE (-3475 2450);
FORCEPROP 1 LAST BODY_TYPE PLUMBING
J 0
(-3475 2500);
DISPLAY 0.872340 (-3475 2500);
PAINT GREEN (-3475 2500);
DISPLAY INVISIBLE (-3475 2500);
FORCEPROP 1 LAST HDL_TAP TRUE
J 0
(-3150 2325);
DISPLAY 0.872340 (-3150 2325);
DISPLAY INVISIBLE (-3150 2325);
FORCEPROP 1 LAST PATH I229
J 0
(-3477 2450);
DISPLAY 0.872340 (-3477 2450);
PAINT GREEN (-3477 2450);
DISPLAY INVISIBLE (-3477 2450);
FORCEADD TAP..1
(-3475 2200);
FORCEPROP 3 LASTPIN (-3525 2200) SIG_NAME M_C_CPU1_SA_CB<5>
J 0
(-3515 2210);
DISPLAY 0.659574 (-3515 2210);
PAINT MONO (-3515 2210);
DISPLAY INVISIBLE (-3515 2210);
FORCEPROP 1 LASTPIN (-3525 2200) BN 5
J 0
(-3537 2208);
DISPLAY 0.489362 (-3537 2208);
PAINT GREEN (-3537 2208);
FORCEPROP 2 LAST CDS_LIB mstr_standard
J 2
(-3475 2200);
DISPLAY 0.723404 (-3475 2200);
PAINT MONO (-3475 2200);
DISPLAY INVISIBLE (-3475 2200);
FORCEPROP 1 LAST BODY_TYPE PLUMBING
J 0
(-3475 2250);
DISPLAY 0.872340 (-3475 2250);
PAINT GREEN (-3475 2250);
DISPLAY INVISIBLE (-3475 2250);
FORCEPROP 1 LAST HDL_TAP TRUE
J 0
(-3150 2075);
DISPLAY 0.872340 (-3150 2075);
DISPLAY INVISIBLE (-3150 2075);
FORCEPROP 1 LAST PATH I230
J 0
(-3477 2200);
DISPLAY 0.872340 (-3477 2200);
PAINT GREEN (-3477 2200);
DISPLAY INVISIBLE (-3477 2200);
FORCEADD TAP..1
(-3475 2250);
FORCEPROP 3 LASTPIN (-3525 2250) SIG_NAME M_C_CPU1_SA_CB<4>
J 0
(-3515 2260);
DISPLAY 0.659574 (-3515 2260);
PAINT MONO (-3515 2260);
DISPLAY INVISIBLE (-3515 2260);
FORCEPROP 1 LASTPIN (-3525 2250) BN 4
J 0
(-3537 2258);
DISPLAY 0.489362 (-3537 2258);
PAINT GREEN (-3537 2258);
FORCEPROP 2 LAST CDS_LIB mstr_standard
J 2
(-3475 2250);
DISPLAY 0.723404 (-3475 2250);
PAINT MONO (-3475 2250);
DISPLAY INVISIBLE (-3475 2250);
FORCEPROP 1 LAST BODY_TYPE PLUMBING
J 0
(-3475 2300);
DISPLAY 0.872340 (-3475 2300);
PAINT GREEN (-3475 2300);
DISPLAY INVISIBLE (-3475 2300);
FORCEPROP 1 LAST HDL_TAP TRUE
J 0
(-3150 2125);
DISPLAY 0.872340 (-3150 2125);
DISPLAY INVISIBLE (-3150 2125);
FORCEPROP 1 LAST PATH I231
J 0
(-3477 2250);
DISPLAY 0.872340 (-3477 2250);
PAINT GREEN (-3477 2250);
DISPLAY INVISIBLE (-3477 2250);
FORCEADD TAP..1
(-3475 2300);
FORCEPROP 3 LASTPIN (-3525 2300) SIG_NAME M_C_CPU1_SA_CB<3>
J 0
(-3515 2310);
DISPLAY 0.659574 (-3515 2310);
PAINT MONO (-3515 2310);
DISPLAY INVISIBLE (-3515 2310);
FORCEPROP 1 LASTPIN (-3525 2300) BN 3
J 0
(-3537 2308);
DISPLAY 0.489362 (-3537 2308);
PAINT GREEN (-3537 2308);
FORCEPROP 2 LAST CDS_LIB mstr_standard
J 2
(-3475 2300);
DISPLAY 0.723404 (-3475 2300);
PAINT MONO (-3475 2300);
DISPLAY INVISIBLE (-3475 2300);
FORCEPROP 1 LAST BODY_TYPE PLUMBING
J 0
(-3475 2350);
DISPLAY 0.872340 (-3475 2350);
PAINT GREEN (-3475 2350);
DISPLAY INVISIBLE (-3475 2350);
FORCEPROP 1 LAST HDL_TAP TRUE
J 0
(-3150 2175);
DISPLAY 0.872340 (-3150 2175);
DISPLAY INVISIBLE (-3150 2175);
FORCEPROP 1 LAST PATH I232
J 0
(-3477 2300);
DISPLAY 0.872340 (-3477 2300);
PAINT GREEN (-3477 2300);
DISPLAY INVISIBLE (-3477 2300);
FORCEADD TAP..1
(-3475 2150);
FORCEPROP 3 LASTPIN (-3525 2150) SIG_NAME M_C_CPU1_SA_CB<6>
J 0
(-3515 2160);
DISPLAY 0.659574 (-3515 2160);
PAINT MONO (-3515 2160);
DISPLAY INVISIBLE (-3515 2160);
FORCEPROP 1 LASTPIN (-3525 2150) BN 6
J 0
(-3537 2158);
DISPLAY 0.489362 (-3537 2158);
PAINT GREEN (-3537 2158);
FORCEPROP 2 LAST CDS_LIB mstr_standard
J 2
(-3475 2150);
DISPLAY 0.723404 (-3475 2150);
PAINT MONO (-3475 2150);
DISPLAY INVISIBLE (-3475 2150);
FORCEPROP 1 LAST BODY_TYPE PLUMBING
J 0
(-3475 2200);
DISPLAY 0.872340 (-3475 2200);
PAINT GREEN (-3475 2200);
DISPLAY INVISIBLE (-3475 2200);
FORCEPROP 1 LAST HDL_TAP TRUE
J 0
(-3150 2025);
DISPLAY 0.872340 (-3150 2025);
DISPLAY INVISIBLE (-3150 2025);
FORCEPROP 1 LAST PATH I233
J 0
(-3477 2150);
DISPLAY 0.872340 (-3477 2150);
PAINT GREEN (-3477 2150);
DISPLAY INVISIBLE (-3477 2150);
FORCEADD TAP..1
(-3475 2100);
FORCEPROP 3 LASTPIN (-3525 2100) SIG_NAME M_C_CPU1_SA_CB<7>
J 0
(-3515 2110);
DISPLAY 0.659574 (-3515 2110);
PAINT MONO (-3515 2110);
DISPLAY INVISIBLE (-3515 2110);
FORCEPROP 1 LASTPIN (-3525 2100) BN 7
J 0
(-3537 2108);
DISPLAY 0.489362 (-3537 2108);
PAINT GREEN (-3537 2108);
FORCEPROP 2 LAST CDS_LIB mstr_standard
J 2
(-3475 2100);
DISPLAY 0.723404 (-3475 2100);
PAINT MONO (-3475 2100);
DISPLAY INVISIBLE (-3475 2100);
FORCEPROP 1 LAST BODY_TYPE PLUMBING
J 0
(-3475 2150);
DISPLAY 0.872340 (-3475 2150);
PAINT GREEN (-3475 2150);
DISPLAY INVISIBLE (-3475 2150);
FORCEPROP 1 LAST HDL_TAP TRUE
J 0
(-3150 1975);
DISPLAY 0.872340 (-3150 1975);
DISPLAY INVISIBLE (-3150 1975);
FORCEPROP 1 LAST PATH I234
J 0
(-3477 2100);
DISPLAY 0.872340 (-3477 2100);
PAINT GREEN (-3477 2100);
DISPLAY INVISIBLE (-3477 2100);
FORCEADD OFFPAGE..6
R 2
(-2875 2050);
FORCEPROP 2 LAST $XR0 100 
J 0
(-2661 2050);
DISPLAY 0.638298 (-2661 2050);
PAINT MONO (-2661 2050);
FORCEPROP 2 LAST CDS_LIB mstr_standard
J 2
(-2875 2050);
DISPLAY 0.723404 (-2875 2050);
PAINT MONO (-2875 2050);
DISPLAY INVISIBLE (-2875 2050);
FORCEPROP 1 LAST OFFPAGE TRUE
J 2
(-3200 1925);
DISPLAY 0.872340 (-3200 1925);
PAINT GREEN (-3200 1925);
DISPLAY INVISIBLE (-3200 1925);
FORCEPROP 1 LAST COMMENT_BODY TRUE
J 2
(-2975 1975);
DISPLAY 0.872340 (-2975 1975);
PAINT GREEN (-2975 1975);
DISPLAY INVISIBLE (-2975 1975);
FORCEPROP 2 LAST PATH I235
J 0
(-2650 2100);
DISPLAY 1.021277 (-2650 2100);
DISPLAY INVISIBLE (-2650 2100);
FORCEADD TAP..1
(-3475 2000);
FORCEPROP 3 LASTPIN (-3525 2000) SIG_NAME M_C_CPU1_SB_CB<0>
J 0
(-3515 2010);
DISPLAY 0.659574 (-3515 2010);
PAINT MONO (-3515 2010);
DISPLAY INVISIBLE (-3515 2010);
FORCEPROP 1 LASTPIN (-3525 2000) BN 0
J 0
(-3537 2008);
DISPLAY 0.489362 (-3537 2008);
PAINT GREEN (-3537 2008);
FORCEPROP 2 LAST CDS_LIB mstr_standard
J 2
(-3475 2000);
DISPLAY 0.723404 (-3475 2000);
PAINT MONO (-3475 2000);
DISPLAY INVISIBLE (-3475 2000);
FORCEPROP 1 LAST BODY_TYPE PLUMBING
J 0
(-3475 2050);
DISPLAY 0.872340 (-3475 2050);
PAINT GREEN (-3475 2050);
DISPLAY INVISIBLE (-3475 2050);
FORCEPROP 1 LAST HDL_TAP TRUE
J 0
(-3150 1875);
DISPLAY 0.872340 (-3150 1875);
DISPLAY INVISIBLE (-3150 1875);
FORCEPROP 1 LAST PATH I236
J 0
(-3477 2000);
DISPLAY 0.872340 (-3477 2000);
PAINT GREEN (-3477 2000);
DISPLAY INVISIBLE (-3477 2000);
FORCEADD TAP..1
(-3475 1950);
FORCEPROP 3 LASTPIN (-3525 1950) SIG_NAME M_C_CPU1_SB_CB<1>
J 0
(-3515 1960);
DISPLAY 0.659574 (-3515 1960);
PAINT MONO (-3515 1960);
DISPLAY INVISIBLE (-3515 1960);
FORCEPROP 1 LASTPIN (-3525 1950) BN 1
J 0
(-3537 1958);
DISPLAY 0.489362 (-3537 1958);
PAINT GREEN (-3537 1958);
FORCEPROP 2 LAST CDS_LIB mstr_standard
J 2
(-3475 1950);
DISPLAY 0.723404 (-3475 1950);
PAINT MONO (-3475 1950);
DISPLAY INVISIBLE (-3475 1950);
FORCEPROP 1 LAST BODY_TYPE PLUMBING
J 0
(-3475 2000);
DISPLAY 0.872340 (-3475 2000);
PAINT GREEN (-3475 2000);
DISPLAY INVISIBLE (-3475 2000);
FORCEPROP 1 LAST HDL_TAP TRUE
J 0
(-3150 1825);
DISPLAY 0.872340 (-3150 1825);
DISPLAY INVISIBLE (-3150 1825);
FORCEPROP 1 LAST PATH I237
J 0
(-3477 1950);
DISPLAY 0.872340 (-3477 1950);
PAINT GREEN (-3477 1950);
DISPLAY INVISIBLE (-3477 1950);
FORCEADD TAP..1
(-3475 1900);
FORCEPROP 3 LASTPIN (-3525 1900) SIG_NAME M_C_CPU1_SB_CB<2>
J 0
(-3515 1910);
DISPLAY 0.659574 (-3515 1910);
PAINT MONO (-3515 1910);
DISPLAY INVISIBLE (-3515 1910);
FORCEPROP 1 LASTPIN (-3525 1900) BN 2
J 0
(-3537 1908);
DISPLAY 0.489362 (-3537 1908);
PAINT GREEN (-3537 1908);
FORCEPROP 2 LAST CDS_LIB mstr_standard
J 2
(-3475 1900);
DISPLAY 0.723404 (-3475 1900);
PAINT MONO (-3475 1900);
DISPLAY INVISIBLE (-3475 1900);
FORCEPROP 1 LAST BODY_TYPE PLUMBING
J 0
(-3475 1950);
DISPLAY 0.872340 (-3475 1950);
PAINT GREEN (-3475 1950);
DISPLAY INVISIBLE (-3475 1950);
FORCEPROP 1 LAST HDL_TAP TRUE
J 0
(-3150 1775);
DISPLAY 0.872340 (-3150 1775);
DISPLAY INVISIBLE (-3150 1775);
FORCEPROP 1 LAST PATH I238
J 0
(-3477 1900);
DISPLAY 0.872340 (-3477 1900);
PAINT GREEN (-3477 1900);
DISPLAY INVISIBLE (-3477 1900);
FORCEADD TAP..1
(-3475 1850);
FORCEPROP 3 LASTPIN (-3525 1850) SIG_NAME M_C_CPU1_SB_CB<3>
J 0
(-3515 1860);
DISPLAY 0.659574 (-3515 1860);
PAINT MONO (-3515 1860);
DISPLAY INVISIBLE (-3515 1860);
FORCEPROP 1 LASTPIN (-3525 1850) BN 3
J 0
(-3537 1858);
DISPLAY 0.489362 (-3537 1858);
PAINT GREEN (-3537 1858);
FORCEPROP 2 LAST CDS_LIB mstr_standard
J 2
(-3475 1850);
DISPLAY 0.723404 (-3475 1850);
PAINT MONO (-3475 1850);
DISPLAY INVISIBLE (-3475 1850);
FORCEPROP 1 LAST BODY_TYPE PLUMBING
J 0
(-3475 1900);
DISPLAY 0.872340 (-3475 1900);
PAINT GREEN (-3475 1900);
DISPLAY INVISIBLE (-3475 1900);
FORCEPROP 1 LAST HDL_TAP TRUE
J 0
(-3150 1725);
DISPLAY 0.872340 (-3150 1725);
DISPLAY INVISIBLE (-3150 1725);
FORCEPROP 1 LAST PATH I239
J 0
(-3477 1850);
DISPLAY 0.872340 (-3477 1850);
PAINT GREEN (-3477 1850);
DISPLAY INVISIBLE (-3477 1850);
FORCEADD TAP..1
(-3475 1800);
FORCEPROP 3 LASTPIN (-3525 1800) SIG_NAME M_C_CPU1_SB_CB<4>
J 0
(-3515 1810);
DISPLAY 0.659574 (-3515 1810);
PAINT MONO (-3515 1810);
DISPLAY INVISIBLE (-3515 1810);
FORCEPROP 1 LASTPIN (-3525 1800) BN 4
J 0
(-3537 1808);
DISPLAY 0.489362 (-3537 1808);
PAINT GREEN (-3537 1808);
FORCEPROP 2 LAST CDS_LIB mstr_standard
J 2
(-3475 1800);
DISPLAY 0.723404 (-3475 1800);
PAINT MONO (-3475 1800);
DISPLAY INVISIBLE (-3475 1800);
FORCEPROP 1 LAST BODY_TYPE PLUMBING
J 0
(-3475 1850);
DISPLAY 0.872340 (-3475 1850);
PAINT GREEN (-3475 1850);
DISPLAY INVISIBLE (-3475 1850);
FORCEPROP 1 LAST HDL_TAP TRUE
J 0
(-3150 1675);
DISPLAY 0.872340 (-3150 1675);
DISPLAY INVISIBLE (-3150 1675);
FORCEPROP 1 LAST PATH I240
J 0
(-3477 1800);
DISPLAY 0.872340 (-3477 1800);
PAINT GREEN (-3477 1800);
DISPLAY INVISIBLE (-3477 1800);
FORCEADD TAP..1
(-3475 1750);
FORCEPROP 3 LASTPIN (-3525 1750) SIG_NAME M_C_CPU1_SB_CB<5>
J 0
(-3515 1760);
DISPLAY 0.659574 (-3515 1760);
PAINT MONO (-3515 1760);
DISPLAY INVISIBLE (-3515 1760);
FORCEPROP 1 LASTPIN (-3525 1750) BN 5
J 0
(-3537 1758);
DISPLAY 0.489362 (-3537 1758);
PAINT GREEN (-3537 1758);
FORCEPROP 2 LAST CDS_LIB mstr_standard
J 2
(-3475 1750);
DISPLAY 0.723404 (-3475 1750);
PAINT MONO (-3475 1750);
DISPLAY INVISIBLE (-3475 1750);
FORCEPROP 1 LAST BODY_TYPE PLUMBING
J 0
(-3475 1800);
DISPLAY 0.872340 (-3475 1800);
PAINT GREEN (-3475 1800);
DISPLAY INVISIBLE (-3475 1800);
FORCEPROP 1 LAST HDL_TAP TRUE
J 0
(-3150 1625);
DISPLAY 0.872340 (-3150 1625);
DISPLAY INVISIBLE (-3150 1625);
FORCEPROP 1 LAST PATH I241
J 0
(-3477 1750);
DISPLAY 0.872340 (-3477 1750);
PAINT GREEN (-3477 1750);
DISPLAY INVISIBLE (-3477 1750);
FORCEADD TAP..1
(-3475 1650);
FORCEPROP 3 LASTPIN (-3525 1650) SIG_NAME M_C_CPU1_SB_CB<7>
J 0
(-3515 1660);
DISPLAY 0.659574 (-3515 1660);
PAINT MONO (-3515 1660);
DISPLAY INVISIBLE (-3515 1660);
FORCEPROP 1 LASTPIN (-3525 1650) BN 7
J 0
(-3537 1658);
DISPLAY 0.489362 (-3537 1658);
PAINT GREEN (-3537 1658);
FORCEPROP 2 LAST CDS_LIB mstr_standard
J 2
(-3475 1650);
DISPLAY 0.723404 (-3475 1650);
PAINT MONO (-3475 1650);
DISPLAY INVISIBLE (-3475 1650);
FORCEPROP 1 LAST BODY_TYPE PLUMBING
J 0
(-3475 1700);
DISPLAY 0.872340 (-3475 1700);
PAINT GREEN (-3475 1700);
DISPLAY INVISIBLE (-3475 1700);
FORCEPROP 1 LAST HDL_TAP TRUE
J 0
(-3150 1525);
DISPLAY 0.872340 (-3150 1525);
DISPLAY INVISIBLE (-3150 1525);
FORCEPROP 1 LAST PATH I242
J 0
(-3477 1650);
DISPLAY 0.872340 (-3477 1650);
PAINT GREEN (-3477 1650);
DISPLAY INVISIBLE (-3477 1650);
FORCEADD TAP..1
(-3475 1700);
FORCEPROP 3 LASTPIN (-3525 1700) SIG_NAME M_C_CPU1_SB_CB<6>
J 0
(-3515 1710);
DISPLAY 0.659574 (-3515 1710);
PAINT MONO (-3515 1710);
DISPLAY INVISIBLE (-3515 1710);
FORCEPROP 1 LASTPIN (-3525 1700) BN 6
J 0
(-3537 1708);
DISPLAY 0.489362 (-3537 1708);
PAINT GREEN (-3537 1708);
FORCEPROP 2 LAST CDS_LIB mstr_standard
J 2
(-3475 1700);
DISPLAY 0.723404 (-3475 1700);
PAINT MONO (-3475 1700);
DISPLAY INVISIBLE (-3475 1700);
FORCEPROP 1 LAST BODY_TYPE PLUMBING
J 0
(-3475 1750);
DISPLAY 0.872340 (-3475 1750);
PAINT GREEN (-3475 1750);
DISPLAY INVISIBLE (-3475 1750);
FORCEPROP 1 LAST HDL_TAP TRUE
J 0
(-3150 1575);
DISPLAY 0.872340 (-3150 1575);
DISPLAY INVISIBLE (-3150 1575);
FORCEPROP 1 LAST PATH I243
J 0
(-3477 1700);
DISPLAY 0.872340 (-3477 1700);
PAINT GREEN (-3477 1700);
DISPLAY INVISIBLE (-3477 1700);
FORCEADD TAP..1
R 2
(-5900 6050);
FORCEPROP 3 LASTPIN (-5850 6050) SIG_NAME M_C_CPU1_SA_DQS_DP<0>
J 0
(-5840 6060);
DISPLAY 0.659574 (-5840 6060);
PAINT MONO (-5840 6060);
DISPLAY INVISIBLE (-5840 6060);
FORCEPROP 1 LASTPIN (-5850 6050) BN 0
J 2
(-5838 6058);
DISPLAY 0.489362 (-5838 6058);
PAINT GREEN (-5838 6058);
FORCEPROP 2 LAST CDS_LIB mstr_standard
J 2
(-5900 6050);
DISPLAY 0.723404 (-5900 6050);
PAINT MONO (-5900 6050);
DISPLAY INVISIBLE (-5900 6050);
FORCEPROP 1 LAST BODY_TYPE PLUMBING
J 2
(-5900 6100);
DISPLAY 0.872340 (-5900 6100);
PAINT GREEN (-5900 6100);
DISPLAY INVISIBLE (-5900 6100);
FORCEPROP 1 LAST HDL_TAP TRUE
J 2
(-6225 5925);
DISPLAY 0.872340 (-6225 5925);
DISPLAY INVISIBLE (-6225 5925);
FORCEPROP 1 LAST PATH I244
J 2
(-5898 6050);
DISPLAY 0.872340 (-5898 6050);
PAINT GREEN (-5898 6050);
DISPLAY INVISIBLE (-5898 6050);
FORCEADD TAP..1
R 2
(-5900 5950);
FORCEPROP 3 LASTPIN (-5850 5950) SIG_NAME M_C_CPU1_SA_DQS_DP<1>
J 0
(-5840 5960);
DISPLAY 0.659574 (-5840 5960);
PAINT MONO (-5840 5960);
DISPLAY INVISIBLE (-5840 5960);
FORCEPROP 1 LASTPIN (-5850 5950) BN 1
J 2
(-5838 5958);
DISPLAY 0.489362 (-5838 5958);
PAINT GREEN (-5838 5958);
FORCEPROP 2 LAST CDS_LIB mstr_standard
J 2
(-5900 5950);
DISPLAY 0.723404 (-5900 5950);
PAINT MONO (-5900 5950);
DISPLAY INVISIBLE (-5900 5950);
FORCEPROP 1 LAST BODY_TYPE PLUMBING
J 2
(-5900 6000);
DISPLAY 0.872340 (-5900 6000);
PAINT GREEN (-5900 6000);
DISPLAY INVISIBLE (-5900 6000);
FORCEPROP 1 LAST HDL_TAP TRUE
J 2
(-6225 5825);
DISPLAY 0.872340 (-6225 5825);
DISPLAY INVISIBLE (-6225 5825);
FORCEPROP 1 LAST PATH I245
J 2
(-5898 5950);
DISPLAY 0.872340 (-5898 5950);
PAINT GREEN (-5898 5950);
DISPLAY INVISIBLE (-5898 5950);
FORCEADD TAP..1
R 2
(-5900 5850);
FORCEPROP 3 LASTPIN (-5850 5850) SIG_NAME M_C_CPU1_SA_DQS_DP<2>
J 0
(-5840 5860);
DISPLAY 0.659574 (-5840 5860);
PAINT MONO (-5840 5860);
DISPLAY INVISIBLE (-5840 5860);
FORCEPROP 1 LASTPIN (-5850 5850) BN 2
J 2
(-5838 5858);
DISPLAY 0.489362 (-5838 5858);
PAINT GREEN (-5838 5858);
FORCEPROP 2 LAST CDS_LIB mstr_standard
J 2
(-5900 5850);
DISPLAY 0.723404 (-5900 5850);
PAINT MONO (-5900 5850);
DISPLAY INVISIBLE (-5900 5850);
FORCEPROP 1 LAST BODY_TYPE PLUMBING
J 2
(-5900 5900);
DISPLAY 0.872340 (-5900 5900);
PAINT GREEN (-5900 5900);
DISPLAY INVISIBLE (-5900 5900);
FORCEPROP 1 LAST HDL_TAP TRUE
J 2
(-6225 5725);
DISPLAY 0.872340 (-6225 5725);
DISPLAY INVISIBLE (-6225 5725);
FORCEPROP 1 LAST PATH I246
J 2
(-5898 5850);
DISPLAY 0.872340 (-5898 5850);
PAINT GREEN (-5898 5850);
DISPLAY INVISIBLE (-5898 5850);
FORCEADD TAP..1
R 2
(-5900 5650);
FORCEPROP 3 LASTPIN (-5850 5650) SIG_NAME M_C_CPU1_SA_DQS_DP<4>
J 0
(-5840 5660);
DISPLAY 0.659574 (-5840 5660);
PAINT MONO (-5840 5660);
DISPLAY INVISIBLE (-5840 5660);
FORCEPROP 1 LASTPIN (-5850 5650) BN 4
J 2
(-5838 5658);
DISPLAY 0.489362 (-5838 5658);
PAINT GREEN (-5838 5658);
FORCEPROP 2 LAST CDS_LIB mstr_standard
J 2
(-5900 5650);
DISPLAY 0.723404 (-5900 5650);
PAINT MONO (-5900 5650);
DISPLAY INVISIBLE (-5900 5650);
FORCEPROP 1 LAST BODY_TYPE PLUMBING
J 2
(-5900 5700);
DISPLAY 0.872340 (-5900 5700);
PAINT GREEN (-5900 5700);
DISPLAY INVISIBLE (-5900 5700);
FORCEPROP 1 LAST HDL_TAP TRUE
J 2
(-6225 5525);
DISPLAY 0.872340 (-6225 5525);
DISPLAY INVISIBLE (-6225 5525);
FORCEPROP 1 LAST PATH I247
J 2
(-5898 5650);
DISPLAY 0.872340 (-5898 5650);
PAINT GREEN (-5898 5650);
DISPLAY INVISIBLE (-5898 5650);
FORCEADD TAP..1
R 2
(-5900 5750);
FORCEPROP 3 LASTPIN (-5850 5750) SIG_NAME M_C_CPU1_SA_DQS_DP<3>
J 0
(-5840 5760);
DISPLAY 0.659574 (-5840 5760);
PAINT MONO (-5840 5760);
DISPLAY INVISIBLE (-5840 5760);
FORCEPROP 1 LASTPIN (-5850 5750) BN 3
J 2
(-5838 5758);
DISPLAY 0.489362 (-5838 5758);
PAINT GREEN (-5838 5758);
FORCEPROP 2 LAST CDS_LIB mstr_standard
J 2
(-5900 5750);
DISPLAY 0.723404 (-5900 5750);
PAINT MONO (-5900 5750);
DISPLAY INVISIBLE (-5900 5750);
FORCEPROP 1 LAST BODY_TYPE PLUMBING
J 2
(-5900 5800);
DISPLAY 0.872340 (-5900 5800);
PAINT GREEN (-5900 5800);
DISPLAY INVISIBLE (-5900 5800);
FORCEPROP 1 LAST HDL_TAP TRUE
J 2
(-6225 5625);
DISPLAY 0.872340 (-6225 5625);
DISPLAY INVISIBLE (-6225 5625);
FORCEPROP 1 LAST PATH I248
J 2
(-5898 5750);
DISPLAY 0.872340 (-5898 5750);
PAINT GREEN (-5898 5750);
DISPLAY INVISIBLE (-5898 5750);
FORCEADD TAP..1
R 2
(-6100 5900);
FORCEPROP 3 LASTPIN (-6050 5900) SIG_NAME M_C_CPU1_SA_DQS_DN<1>
J 0
(-6040 5910);
DISPLAY 0.659574 (-6040 5910);
PAINT MONO (-6040 5910);
DISPLAY INVISIBLE (-6040 5910);
FORCEPROP 1 LASTPIN (-6050 5900) BN 1
J 2
(-6038 5908);
DISPLAY 0.489362 (-6038 5908);
PAINT GREEN (-6038 5908);
FORCEPROP 2 LAST CDS_LIB mstr_standard
J 2
(-6100 5900);
DISPLAY 0.723404 (-6100 5900);
PAINT MONO (-6100 5900);
DISPLAY INVISIBLE (-6100 5900);
FORCEPROP 1 LAST BODY_TYPE PLUMBING
J 2
(-6100 5950);
DISPLAY 0.872340 (-6100 5950);
PAINT GREEN (-6100 5950);
DISPLAY INVISIBLE (-6100 5950);
FORCEPROP 1 LAST HDL_TAP TRUE
J 2
(-6425 5775);
DISPLAY 0.872340 (-6425 5775);
DISPLAY INVISIBLE (-6425 5775);
FORCEPROP 1 LAST PATH I249
J 2
(-6098 5900);
DISPLAY 0.872340 (-6098 5900);
PAINT GREEN (-6098 5900);
DISPLAY INVISIBLE (-6098 5900);
FORCEADD TAP..1
R 2
(-6100 6000);
FORCEPROP 3 LASTPIN (-6050 6000) SIG_NAME M_C_CPU1_SA_DQS_DN<0>
J 0
(-6040 6010);
DISPLAY 0.659574 (-6040 6010);
PAINT MONO (-6040 6010);
DISPLAY INVISIBLE (-6040 6010);
FORCEPROP 1 LASTPIN (-6050 6000) BN 0
J 2
(-6038 6008);
DISPLAY 0.489362 (-6038 6008);
PAINT GREEN (-6038 6008);
FORCEPROP 2 LAST CDS_LIB mstr_standard
J 2
(-6100 6000);
DISPLAY 0.723404 (-6100 6000);
PAINT MONO (-6100 6000);
DISPLAY INVISIBLE (-6100 6000);
FORCEPROP 1 LAST BODY_TYPE PLUMBING
J 2
(-6100 6050);
DISPLAY 0.872340 (-6100 6050);
PAINT GREEN (-6100 6050);
DISPLAY INVISIBLE (-6100 6050);
FORCEPROP 1 LAST HDL_TAP TRUE
J 2
(-6425 5875);
DISPLAY 0.872340 (-6425 5875);
DISPLAY INVISIBLE (-6425 5875);
FORCEPROP 1 LAST PATH I250
J 2
(-6098 6000);
DISPLAY 0.872340 (-6098 6000);
PAINT GREEN (-6098 6000);
DISPLAY INVISIBLE (-6098 6000);
FORCEADD TAP..1
R 2
(-6100 5800);
FORCEPROP 3 LASTPIN (-6050 5800) SIG_NAME M_C_CPU1_SA_DQS_DN<2>
J 0
(-6040 5810);
DISPLAY 0.659574 (-6040 5810);
PAINT MONO (-6040 5810);
DISPLAY INVISIBLE (-6040 5810);
FORCEPROP 1 LASTPIN (-6050 5800) BN 2
J 2
(-6038 5808);
DISPLAY 0.489362 (-6038 5808);
PAINT GREEN (-6038 5808);
FORCEPROP 2 LAST CDS_LIB mstr_standard
J 2
(-6100 5800);
DISPLAY 0.723404 (-6100 5800);
PAINT MONO (-6100 5800);
DISPLAY INVISIBLE (-6100 5800);
FORCEPROP 1 LAST BODY_TYPE PLUMBING
J 2
(-6100 5850);
DISPLAY 0.872340 (-6100 5850);
PAINT GREEN (-6100 5850);
DISPLAY INVISIBLE (-6100 5850);
FORCEPROP 1 LAST HDL_TAP TRUE
J 2
(-6425 5675);
DISPLAY 0.872340 (-6425 5675);
DISPLAY INVISIBLE (-6425 5675);
FORCEPROP 1 LAST PATH I251
J 2
(-6098 5800);
DISPLAY 0.872340 (-6098 5800);
PAINT GREEN (-6098 5800);
DISPLAY INVISIBLE (-6098 5800);
FORCEADD TAP..1
R 2
(-6100 5700);
FORCEPROP 3 LASTPIN (-6050 5700) SIG_NAME M_C_CPU1_SA_DQS_DN<3>
J 0
(-6040 5710);
DISPLAY 0.659574 (-6040 5710);
PAINT MONO (-6040 5710);
DISPLAY INVISIBLE (-6040 5710);
FORCEPROP 1 LASTPIN (-6050 5700) BN 3
J 2
(-6038 5708);
DISPLAY 0.489362 (-6038 5708);
PAINT GREEN (-6038 5708);
FORCEPROP 2 LAST CDS_LIB mstr_standard
J 2
(-6100 5700);
DISPLAY 0.723404 (-6100 5700);
PAINT MONO (-6100 5700);
DISPLAY INVISIBLE (-6100 5700);
FORCEPROP 1 LAST BODY_TYPE PLUMBING
J 2
(-6100 5750);
DISPLAY 0.872340 (-6100 5750);
PAINT GREEN (-6100 5750);
DISPLAY INVISIBLE (-6100 5750);
FORCEPROP 1 LAST HDL_TAP TRUE
J 2
(-6425 5575);
DISPLAY 0.872340 (-6425 5575);
DISPLAY INVISIBLE (-6425 5575);
FORCEPROP 1 LAST PATH I252
J 2
(-6098 5700);
DISPLAY 0.872340 (-6098 5700);
PAINT GREEN (-6098 5700);
DISPLAY INVISIBLE (-6098 5700);
FORCEADD TAP..1
R 2
(-5900 5550);
FORCEPROP 3 LASTPIN (-5850 5550) SIG_NAME M_C_CPU1_SA_DQS_DP<5>
J 0
(-5840 5560);
DISPLAY 0.659574 (-5840 5560);
PAINT MONO (-5840 5560);
DISPLAY INVISIBLE (-5840 5560);
FORCEPROP 1 LASTPIN (-5850 5550) BN 5
J 2
(-5838 5558);
DISPLAY 0.489362 (-5838 5558);
PAINT GREEN (-5838 5558);
FORCEPROP 2 LAST CDS_LIB mstr_standard
J 2
(-5900 5550);
DISPLAY 0.723404 (-5900 5550);
PAINT MONO (-5900 5550);
DISPLAY INVISIBLE (-5900 5550);
FORCEPROP 1 LAST BODY_TYPE PLUMBING
J 2
(-5900 5600);
DISPLAY 0.872340 (-5900 5600);
PAINT GREEN (-5900 5600);
DISPLAY INVISIBLE (-5900 5600);
FORCEPROP 1 LAST HDL_TAP TRUE
J 2
(-6225 5425);
DISPLAY 0.872340 (-6225 5425);
DISPLAY INVISIBLE (-6225 5425);
FORCEPROP 1 LAST PATH I253
J 2
(-5898 5550);
DISPLAY 0.872340 (-5898 5550);
PAINT GREEN (-5898 5550);
DISPLAY INVISIBLE (-5898 5550);
FORCEADD TAP..1
R 2
(-5900 5450);
FORCEPROP 3 LASTPIN (-5850 5450) SIG_NAME M_C_CPU1_SA_DQS_DP<6>
J 0
(-5840 5460);
DISPLAY 0.659574 (-5840 5460);
PAINT MONO (-5840 5460);
DISPLAY INVISIBLE (-5840 5460);
FORCEPROP 1 LASTPIN (-5850 5450) BN 6
J 2
(-5838 5458);
DISPLAY 0.489362 (-5838 5458);
PAINT GREEN (-5838 5458);
FORCEPROP 2 LAST CDS_LIB mstr_standard
J 2
(-5900 5450);
DISPLAY 0.723404 (-5900 5450);
PAINT MONO (-5900 5450);
DISPLAY INVISIBLE (-5900 5450);
FORCEPROP 1 LAST BODY_TYPE PLUMBING
J 2
(-5900 5500);
DISPLAY 0.872340 (-5900 5500);
PAINT GREEN (-5900 5500);
DISPLAY INVISIBLE (-5900 5500);
FORCEPROP 1 LAST HDL_TAP TRUE
J 2
(-6225 5325);
DISPLAY 0.872340 (-6225 5325);
DISPLAY INVISIBLE (-6225 5325);
FORCEPROP 1 LAST PATH I254
J 2
(-5898 5450);
DISPLAY 0.872340 (-5898 5450);
PAINT GREEN (-5898 5450);
DISPLAY INVISIBLE (-5898 5450);
FORCEADD TAP..1
R 2
(-5900 5250);
FORCEPROP 3 LASTPIN (-5850 5250) SIG_NAME M_C_CPU1_SA_DQS_DP<8>
J 0
(-5840 5260);
DISPLAY 0.659574 (-5840 5260);
PAINT MONO (-5840 5260);
DISPLAY INVISIBLE (-5840 5260);
FORCEPROP 1 LASTPIN (-5850 5250) BN 8
J 2
(-5838 5258);
DISPLAY 0.489362 (-5838 5258);
PAINT GREEN (-5838 5258);
FORCEPROP 2 LAST CDS_LIB mstr_standard
J 2
(-5900 5250);
DISPLAY 0.723404 (-5900 5250);
PAINT MONO (-5900 5250);
DISPLAY INVISIBLE (-5900 5250);
FORCEPROP 1 LAST BODY_TYPE PLUMBING
J 2
(-5900 5300);
DISPLAY 0.872340 (-5900 5300);
PAINT GREEN (-5900 5300);
DISPLAY INVISIBLE (-5900 5300);
FORCEPROP 1 LAST HDL_TAP TRUE
J 2
(-6225 5125);
DISPLAY 0.872340 (-6225 5125);
DISPLAY INVISIBLE (-6225 5125);
FORCEPROP 1 LAST PATH I255
J 2
(-5898 5250);
DISPLAY 0.872340 (-5898 5250);
PAINT GREEN (-5898 5250);
DISPLAY INVISIBLE (-5898 5250);
FORCEADD TAP..1
R 2
(-5900 5350);
FORCEPROP 3 LASTPIN (-5850 5350) SIG_NAME M_C_CPU1_SA_DQS_DP<7>
J 0
(-5840 5360);
DISPLAY 0.659574 (-5840 5360);
PAINT MONO (-5840 5360);
DISPLAY INVISIBLE (-5840 5360);
FORCEPROP 1 LASTPIN (-5850 5350) BN 7
J 2
(-5838 5358);
DISPLAY 0.489362 (-5838 5358);
PAINT GREEN (-5838 5358);
FORCEPROP 2 LAST CDS_LIB mstr_standard
J 2
(-5900 5350);
DISPLAY 0.723404 (-5900 5350);
PAINT MONO (-5900 5350);
DISPLAY INVISIBLE (-5900 5350);
FORCEPROP 1 LAST BODY_TYPE PLUMBING
J 2
(-5900 5400);
DISPLAY 0.872340 (-5900 5400);
PAINT GREEN (-5900 5400);
DISPLAY INVISIBLE (-5900 5400);
FORCEPROP 1 LAST HDL_TAP TRUE
J 2
(-6225 5225);
DISPLAY 0.872340 (-6225 5225);
DISPLAY INVISIBLE (-6225 5225);
FORCEPROP 1 LAST PATH I256
J 2
(-5898 5350);
DISPLAY 0.872340 (-5898 5350);
PAINT GREEN (-5898 5350);
DISPLAY INVISIBLE (-5898 5350);
FORCEADD TAP..1
R 2
(-5900 5150);
FORCEPROP 3 LASTPIN (-5850 5150) SIG_NAME M_C_CPU1_SA_DQS_DP<9>
J 0
(-5840 5160);
DISPLAY 0.659574 (-5840 5160);
PAINT MONO (-5840 5160);
DISPLAY INVISIBLE (-5840 5160);
FORCEPROP 1 LASTPIN (-5850 5150) BN 9
J 2
(-5838 5158);
DISPLAY 0.489362 (-5838 5158);
PAINT GREEN (-5838 5158);
FORCEPROP 2 LAST CDS_LIB mstr_standard
J 2
(-5900 5150);
DISPLAY 0.723404 (-5900 5150);
PAINT MONO (-5900 5150);
DISPLAY INVISIBLE (-5900 5150);
FORCEPROP 1 LAST BODY_TYPE PLUMBING
J 2
(-5900 5200);
DISPLAY 0.872340 (-5900 5200);
PAINT GREEN (-5900 5200);
DISPLAY INVISIBLE (-5900 5200);
FORCEPROP 1 LAST HDL_TAP TRUE
J 2
(-6225 5025);
DISPLAY 0.872340 (-6225 5025);
DISPLAY INVISIBLE (-6225 5025);
FORCEPROP 1 LAST PATH I257
J 2
(-5898 5150);
DISPLAY 0.872340 (-5898 5150);
PAINT GREEN (-5898 5150);
DISPLAY INVISIBLE (-5898 5150);
FORCEADD TAP..1
R 2
(-6100 5500);
FORCEPROP 3 LASTPIN (-6050 5500) SIG_NAME M_C_CPU1_SA_DQS_DN<5>
J 0
(-6040 5510);
DISPLAY 0.659574 (-6040 5510);
PAINT MONO (-6040 5510);
DISPLAY INVISIBLE (-6040 5510);
FORCEPROP 1 LASTPIN (-6050 5500) BN 5
J 2
(-6038 5508);
DISPLAY 0.489362 (-6038 5508);
PAINT GREEN (-6038 5508);
FORCEPROP 2 LAST CDS_LIB mstr_standard
J 2
(-6100 5500);
DISPLAY 0.723404 (-6100 5500);
PAINT MONO (-6100 5500);
DISPLAY INVISIBLE (-6100 5500);
FORCEPROP 1 LAST BODY_TYPE PLUMBING
J 2
(-6100 5550);
DISPLAY 0.872340 (-6100 5550);
PAINT GREEN (-6100 5550);
DISPLAY INVISIBLE (-6100 5550);
FORCEPROP 1 LAST HDL_TAP TRUE
J 2
(-6425 5375);
DISPLAY 0.872340 (-6425 5375);
DISPLAY INVISIBLE (-6425 5375);
FORCEPROP 1 LAST PATH I258
J 2
(-6098 5500);
DISPLAY 0.872340 (-6098 5500);
PAINT GREEN (-6098 5500);
DISPLAY INVISIBLE (-6098 5500);
FORCEADD TAP..1
R 2
(-6100 5600);
FORCEPROP 3 LASTPIN (-6050 5600) SIG_NAME M_C_CPU1_SA_DQS_DN<4>
J 0
(-6040 5610);
DISPLAY 0.659574 (-6040 5610);
PAINT MONO (-6040 5610);
DISPLAY INVISIBLE (-6040 5610);
FORCEPROP 1 LASTPIN (-6050 5600) BN 4
J 2
(-6038 5608);
DISPLAY 0.489362 (-6038 5608);
PAINT GREEN (-6038 5608);
FORCEPROP 2 LAST CDS_LIB mstr_standard
J 2
(-6100 5600);
DISPLAY 0.723404 (-6100 5600);
PAINT MONO (-6100 5600);
DISPLAY INVISIBLE (-6100 5600);
FORCEPROP 1 LAST BODY_TYPE PLUMBING
J 2
(-6100 5650);
DISPLAY 0.872340 (-6100 5650);
PAINT GREEN (-6100 5650);
DISPLAY INVISIBLE (-6100 5650);
FORCEPROP 1 LAST HDL_TAP TRUE
J 2
(-6425 5475);
DISPLAY 0.872340 (-6425 5475);
DISPLAY INVISIBLE (-6425 5475);
FORCEPROP 1 LAST PATH I259
J 2
(-6098 5600);
DISPLAY 0.872340 (-6098 5600);
PAINT GREEN (-6098 5600);
DISPLAY INVISIBLE (-6098 5600);
FORCEADD TAP..1
R 2
(-6100 5400);
FORCEPROP 3 LASTPIN (-6050 5400) SIG_NAME M_C_CPU1_SA_DQS_DN<6>
J 0
(-6040 5410);
DISPLAY 0.659574 (-6040 5410);
PAINT MONO (-6040 5410);
DISPLAY INVISIBLE (-6040 5410);
FORCEPROP 1 LASTPIN (-6050 5400) BN 6
J 2
(-6038 5408);
DISPLAY 0.489362 (-6038 5408);
PAINT GREEN (-6038 5408);
FORCEPROP 2 LAST CDS_LIB mstr_standard
J 2
(-6100 5400);
DISPLAY 0.723404 (-6100 5400);
PAINT MONO (-6100 5400);
DISPLAY INVISIBLE (-6100 5400);
FORCEPROP 1 LAST BODY_TYPE PLUMBING
J 2
(-6100 5450);
DISPLAY 0.872340 (-6100 5450);
PAINT GREEN (-6100 5450);
DISPLAY INVISIBLE (-6100 5450);
FORCEPROP 1 LAST HDL_TAP TRUE
J 2
(-6425 5275);
DISPLAY 0.872340 (-6425 5275);
DISPLAY INVISIBLE (-6425 5275);
FORCEPROP 1 LAST PATH I260
J 2
(-6098 5400);
DISPLAY 0.872340 (-6098 5400);
PAINT GREEN (-6098 5400);
DISPLAY INVISIBLE (-6098 5400);
FORCEADD TAP..1
R 2
(-6100 5300);
FORCEPROP 3 LASTPIN (-6050 5300) SIG_NAME M_C_CPU1_SA_DQS_DN<7>
J 0
(-6040 5310);
DISPLAY 0.659574 (-6040 5310);
PAINT MONO (-6040 5310);
DISPLAY INVISIBLE (-6040 5310);
FORCEPROP 1 LASTPIN (-6050 5300) BN 7
J 2
(-6038 5308);
DISPLAY 0.489362 (-6038 5308);
PAINT GREEN (-6038 5308);
FORCEPROP 2 LAST CDS_LIB mstr_standard
J 2
(-6100 5300);
DISPLAY 0.723404 (-6100 5300);
PAINT MONO (-6100 5300);
DISPLAY INVISIBLE (-6100 5300);
FORCEPROP 1 LAST BODY_TYPE PLUMBING
J 2
(-6100 5350);
DISPLAY 0.872340 (-6100 5350);
PAINT GREEN (-6100 5350);
DISPLAY INVISIBLE (-6100 5350);
FORCEPROP 1 LAST HDL_TAP TRUE
J 2
(-6425 5175);
DISPLAY 0.872340 (-6425 5175);
DISPLAY INVISIBLE (-6425 5175);
FORCEPROP 1 LAST PATH I261
J 2
(-6098 5300);
DISPLAY 0.872340 (-6098 5300);
PAINT GREEN (-6098 5300);
DISPLAY INVISIBLE (-6098 5300);
FORCEADD TAP..1
R 2
(-6100 5200);
FORCEPROP 3 LASTPIN (-6050 5200) SIG_NAME M_C_CPU1_SA_DQS_DN<8>
J 0
(-6040 5210);
DISPLAY 0.659574 (-6040 5210);
PAINT MONO (-6040 5210);
DISPLAY INVISIBLE (-6040 5210);
FORCEPROP 1 LASTPIN (-6050 5200) BN 8
J 2
(-6038 5208);
DISPLAY 0.489362 (-6038 5208);
PAINT GREEN (-6038 5208);
FORCEPROP 2 LAST CDS_LIB mstr_standard
J 2
(-6100 5200);
DISPLAY 0.723404 (-6100 5200);
PAINT MONO (-6100 5200);
DISPLAY INVISIBLE (-6100 5200);
FORCEPROP 1 LAST BODY_TYPE PLUMBING
J 2
(-6100 5250);
DISPLAY 0.872340 (-6100 5250);
PAINT GREEN (-6100 5250);
DISPLAY INVISIBLE (-6100 5250);
FORCEPROP 1 LAST HDL_TAP TRUE
J 2
(-6425 5075);
DISPLAY 0.872340 (-6425 5075);
DISPLAY INVISIBLE (-6425 5075);
FORCEPROP 1 LAST PATH I262
J 2
(-6098 5200);
DISPLAY 0.872340 (-6098 5200);
PAINT GREEN (-6098 5200);
DISPLAY INVISIBLE (-6098 5200);
FORCEADD TAP..1
R 2
(-5900 5000);
FORCEPROP 3 LASTPIN (-5850 5000) SIG_NAME M_C_CPU1_SB_DQS_DP<0>
J 0
(-5840 5010);
DISPLAY 0.659574 (-5840 5010);
PAINT MONO (-5840 5010);
DISPLAY INVISIBLE (-5840 5010);
FORCEPROP 1 LASTPIN (-5850 5000) BN 0
J 2
(-5838 5008);
DISPLAY 0.489362 (-5838 5008);
PAINT GREEN (-5838 5008);
FORCEPROP 2 LAST CDS_LIB mstr_standard
J 2
(-5900 5000);
DISPLAY 0.723404 (-5900 5000);
PAINT MONO (-5900 5000);
DISPLAY INVISIBLE (-5900 5000);
FORCEPROP 1 LAST BODY_TYPE PLUMBING
J 2
(-5900 5050);
DISPLAY 0.872340 (-5900 5050);
PAINT GREEN (-5900 5050);
DISPLAY INVISIBLE (-5900 5050);
FORCEPROP 1 LAST HDL_TAP TRUE
J 2
(-6225 4875);
DISPLAY 0.872340 (-6225 4875);
DISPLAY INVISIBLE (-6225 4875);
FORCEPROP 1 LAST PATH I263
J 2
(-5898 5000);
DISPLAY 0.872340 (-5898 5000);
PAINT GREEN (-5898 5000);
DISPLAY INVISIBLE (-5898 5000);
FORCEADD TAP..1
R 2
(-5900 4900);
FORCEPROP 3 LASTPIN (-5850 4900) SIG_NAME M_C_CPU1_SB_DQS_DP<1>
J 0
(-5840 4910);
DISPLAY 0.659574 (-5840 4910);
PAINT MONO (-5840 4910);
DISPLAY INVISIBLE (-5840 4910);
FORCEPROP 1 LASTPIN (-5850 4900) BN 1
J 2
(-5838 4908);
DISPLAY 0.489362 (-5838 4908);
PAINT GREEN (-5838 4908);
FORCEPROP 2 LAST CDS_LIB mstr_standard
J 2
(-5900 4900);
DISPLAY 0.723404 (-5900 4900);
PAINT MONO (-5900 4900);
DISPLAY INVISIBLE (-5900 4900);
FORCEPROP 1 LAST BODY_TYPE PLUMBING
J 2
(-5900 4950);
DISPLAY 0.872340 (-5900 4950);
PAINT GREEN (-5900 4950);
DISPLAY INVISIBLE (-5900 4950);
FORCEPROP 1 LAST HDL_TAP TRUE
J 2
(-6225 4775);
DISPLAY 0.872340 (-6225 4775);
DISPLAY INVISIBLE (-6225 4775);
FORCEPROP 1 LAST PATH I264
J 2
(-5898 4900);
DISPLAY 0.872340 (-5898 4900);
PAINT GREEN (-5898 4900);
DISPLAY INVISIBLE (-5898 4900);
FORCEADD TAP..1
R 2
(-5900 4800);
FORCEPROP 3 LASTPIN (-5850 4800) SIG_NAME M_C_CPU1_SB_DQS_DP<2>
J 0
(-5840 4810);
DISPLAY 0.659574 (-5840 4810);
PAINT MONO (-5840 4810);
DISPLAY INVISIBLE (-5840 4810);
FORCEPROP 1 LASTPIN (-5850 4800) BN 2
J 2
(-5838 4808);
DISPLAY 0.489362 (-5838 4808);
PAINT GREEN (-5838 4808);
FORCEPROP 2 LAST CDS_LIB mstr_standard
J 2
(-5900 4800);
DISPLAY 0.723404 (-5900 4800);
PAINT MONO (-5900 4800);
DISPLAY INVISIBLE (-5900 4800);
FORCEPROP 1 LAST BODY_TYPE PLUMBING
J 2
(-5900 4850);
DISPLAY 0.872340 (-5900 4850);
PAINT GREEN (-5900 4850);
DISPLAY INVISIBLE (-5900 4850);
FORCEPROP 1 LAST HDL_TAP TRUE
J 2
(-6225 4675);
DISPLAY 0.872340 (-6225 4675);
DISPLAY INVISIBLE (-6225 4675);
FORCEPROP 1 LAST PATH I265
J 2
(-5898 4800);
DISPLAY 0.872340 (-5898 4800);
PAINT GREEN (-5898 4800);
DISPLAY INVISIBLE (-5898 4800);
FORCEADD TAP..1
R 2
(-5900 4700);
FORCEPROP 3 LASTPIN (-5850 4700) SIG_NAME M_C_CPU1_SB_DQS_DP<3>
J 0
(-5840 4710);
DISPLAY 0.659574 (-5840 4710);
PAINT MONO (-5840 4710);
DISPLAY INVISIBLE (-5840 4710);
FORCEPROP 1 LASTPIN (-5850 4700) BN 3
J 2
(-5838 4708);
DISPLAY 0.489362 (-5838 4708);
PAINT GREEN (-5838 4708);
FORCEPROP 2 LAST CDS_LIB mstr_standard
J 2
(-5900 4700);
DISPLAY 0.723404 (-5900 4700);
PAINT MONO (-5900 4700);
DISPLAY INVISIBLE (-5900 4700);
FORCEPROP 1 LAST BODY_TYPE PLUMBING
J 2
(-5900 4750);
DISPLAY 0.872340 (-5900 4750);
PAINT GREEN (-5900 4750);
DISPLAY INVISIBLE (-5900 4750);
FORCEPROP 1 LAST HDL_TAP TRUE
J 2
(-6225 4575);
DISPLAY 0.872340 (-6225 4575);
DISPLAY INVISIBLE (-6225 4575);
FORCEPROP 1 LAST PATH I266
J 2
(-5898 4700);
DISPLAY 0.872340 (-5898 4700);
PAINT GREEN (-5898 4700);
DISPLAY INVISIBLE (-5898 4700);
FORCEADD TAP..1
R 2
(-6100 5100);
FORCEPROP 3 LASTPIN (-6050 5100) SIG_NAME M_C_CPU1_SA_DQS_DN<9>
J 0
(-6040 5110);
DISPLAY 0.659574 (-6040 5110);
PAINT MONO (-6040 5110);
DISPLAY INVISIBLE (-6040 5110);
FORCEPROP 1 LASTPIN (-6050 5100) BN 9
J 2
(-6038 5108);
DISPLAY 0.489362 (-6038 5108);
PAINT GREEN (-6038 5108);
FORCEPROP 2 LAST CDS_LIB mstr_standard
J 2
(-6100 5100);
DISPLAY 0.723404 (-6100 5100);
PAINT MONO (-6100 5100);
DISPLAY INVISIBLE (-6100 5100);
FORCEPROP 1 LAST BODY_TYPE PLUMBING
J 2
(-6100 5150);
DISPLAY 0.872340 (-6100 5150);
PAINT GREEN (-6100 5150);
DISPLAY INVISIBLE (-6100 5150);
FORCEPROP 1 LAST HDL_TAP TRUE
J 2
(-6425 4975);
DISPLAY 0.872340 (-6425 4975);
DISPLAY INVISIBLE (-6425 4975);
FORCEPROP 1 LAST PATH I267
J 2
(-6098 5100);
DISPLAY 0.872340 (-6098 5100);
PAINT GREEN (-6098 5100);
DISPLAY INVISIBLE (-6098 5100);
FORCEADD TAP..1
R 2
(-6100 4950);
FORCEPROP 3 LASTPIN (-6050 4950) SIG_NAME M_C_CPU1_SB_DQS_DN<0>
J 0
(-6040 4960);
DISPLAY 0.659574 (-6040 4960);
PAINT MONO (-6040 4960);
DISPLAY INVISIBLE (-6040 4960);
FORCEPROP 1 LASTPIN (-6050 4950) BN 0
J 2
(-6038 4958);
DISPLAY 0.489362 (-6038 4958);
PAINT GREEN (-6038 4958);
FORCEPROP 2 LAST CDS_LIB mstr_standard
J 2
(-6100 4950);
DISPLAY 0.723404 (-6100 4950);
PAINT MONO (-6100 4950);
DISPLAY INVISIBLE (-6100 4950);
FORCEPROP 1 LAST BODY_TYPE PLUMBING
J 2
(-6100 5000);
DISPLAY 0.872340 (-6100 5000);
PAINT GREEN (-6100 5000);
DISPLAY INVISIBLE (-6100 5000);
FORCEPROP 1 LAST HDL_TAP TRUE
J 2
(-6425 4825);
DISPLAY 0.872340 (-6425 4825);
DISPLAY INVISIBLE (-6425 4825);
FORCEPROP 1 LAST PATH I268
J 2
(-6098 4950);
DISPLAY 0.872340 (-6098 4950);
PAINT GREEN (-6098 4950);
DISPLAY INVISIBLE (-6098 4950);
FORCEADD TAP..1
R 2
(-6100 4850);
FORCEPROP 3 LASTPIN (-6050 4850) SIG_NAME M_C_CPU1_SB_DQS_DN<1>
J 0
(-6040 4860);
DISPLAY 0.659574 (-6040 4860);
PAINT MONO (-6040 4860);
DISPLAY INVISIBLE (-6040 4860);
FORCEPROP 1 LASTPIN (-6050 4850) BN 1
J 2
(-6038 4858);
DISPLAY 0.489362 (-6038 4858);
PAINT GREEN (-6038 4858);
FORCEPROP 2 LAST CDS_LIB mstr_standard
J 2
(-6100 4850);
DISPLAY 0.723404 (-6100 4850);
PAINT MONO (-6100 4850);
DISPLAY INVISIBLE (-6100 4850);
FORCEPROP 1 LAST BODY_TYPE PLUMBING
J 2
(-6100 4900);
DISPLAY 0.872340 (-6100 4900);
PAINT GREEN (-6100 4900);
DISPLAY INVISIBLE (-6100 4900);
FORCEPROP 1 LAST HDL_TAP TRUE
J 2
(-6425 4725);
DISPLAY 0.872340 (-6425 4725);
DISPLAY INVISIBLE (-6425 4725);
FORCEPROP 1 LAST PATH I269
J 2
(-6098 4850);
DISPLAY 0.872340 (-6098 4850);
PAINT GREEN (-6098 4850);
DISPLAY INVISIBLE (-6098 4850);
FORCEADD TAP..1
R 2
(-6100 4750);
FORCEPROP 3 LASTPIN (-6050 4750) SIG_NAME M_C_CPU1_SB_DQS_DN<2>
J 0
(-6040 4760);
DISPLAY 0.659574 (-6040 4760);
PAINT MONO (-6040 4760);
DISPLAY INVISIBLE (-6040 4760);
FORCEPROP 1 LASTPIN (-6050 4750) BN 2
J 2
(-6038 4758);
DISPLAY 0.489362 (-6038 4758);
PAINT GREEN (-6038 4758);
FORCEPROP 2 LAST CDS_LIB mstr_standard
J 2
(-6100 4750);
DISPLAY 0.723404 (-6100 4750);
PAINT MONO (-6100 4750);
DISPLAY INVISIBLE (-6100 4750);
FORCEPROP 1 LAST BODY_TYPE PLUMBING
J 2
(-6100 4800);
DISPLAY 0.872340 (-6100 4800);
PAINT GREEN (-6100 4800);
DISPLAY INVISIBLE (-6100 4800);
FORCEPROP 1 LAST HDL_TAP TRUE
J 2
(-6425 4625);
DISPLAY 0.872340 (-6425 4625);
DISPLAY INVISIBLE (-6425 4625);
FORCEPROP 1 LAST PATH I270
J 2
(-6098 4750);
DISPLAY 0.872340 (-6098 4750);
PAINT GREEN (-6098 4750);
DISPLAY INVISIBLE (-6098 4750);
FORCEADD TAP..1
R 2
(-6100 4650);
FORCEPROP 3 LASTPIN (-6050 4650) SIG_NAME M_C_CPU1_SB_DQS_DN<3>
J 0
(-6040 4660);
DISPLAY 0.659574 (-6040 4660);
PAINT MONO (-6040 4660);
DISPLAY INVISIBLE (-6040 4660);
FORCEPROP 1 LASTPIN (-6050 4650) BN 3
J 2
(-6038 4658);
DISPLAY 0.489362 (-6038 4658);
PAINT GREEN (-6038 4658);
FORCEPROP 2 LAST CDS_LIB mstr_standard
J 2
(-6100 4650);
DISPLAY 0.723404 (-6100 4650);
PAINT MONO (-6100 4650);
DISPLAY INVISIBLE (-6100 4650);
FORCEPROP 1 LAST BODY_TYPE PLUMBING
J 2
(-6100 4700);
DISPLAY 0.872340 (-6100 4700);
PAINT GREEN (-6100 4700);
DISPLAY INVISIBLE (-6100 4700);
FORCEPROP 1 LAST HDL_TAP TRUE
J 2
(-6425 4525);
DISPLAY 0.872340 (-6425 4525);
DISPLAY INVISIBLE (-6425 4525);
FORCEPROP 1 LAST PATH I271
J 2
(-6098 4650);
DISPLAY 0.872340 (-6098 4650);
PAINT GREEN (-6098 4650);
DISPLAY INVISIBLE (-6098 4650);
FORCEADD TAP..1
R 2
(-5900 4500);
FORCEPROP 3 LASTPIN (-5850 4500) SIG_NAME M_C_CPU1_SB_DQS_DP<5>
J 0
(-5840 4510);
DISPLAY 0.659574 (-5840 4510);
PAINT MONO (-5840 4510);
DISPLAY INVISIBLE (-5840 4510);
FORCEPROP 1 LASTPIN (-5850 4500) BN 5
J 2
(-5838 4508);
DISPLAY 0.489362 (-5838 4508);
PAINT GREEN (-5838 4508);
FORCEPROP 2 LAST CDS_LIB mstr_standard
J 2
(-5900 4500);
DISPLAY 0.723404 (-5900 4500);
PAINT MONO (-5900 4500);
DISPLAY INVISIBLE (-5900 4500);
FORCEPROP 1 LAST BODY_TYPE PLUMBING
J 2
(-5900 4550);
DISPLAY 0.872340 (-5900 4550);
PAINT GREEN (-5900 4550);
DISPLAY INVISIBLE (-5900 4550);
FORCEPROP 1 LAST HDL_TAP TRUE
J 2
(-6225 4375);
DISPLAY 0.872340 (-6225 4375);
DISPLAY INVISIBLE (-6225 4375);
FORCEPROP 1 LAST PATH I272
J 2
(-5898 4500);
DISPLAY 0.872340 (-5898 4500);
PAINT GREEN (-5898 4500);
DISPLAY INVISIBLE (-5898 4500);
FORCEADD TAP..1
R 2
(-5900 4600);
FORCEPROP 3 LASTPIN (-5850 4600) SIG_NAME M_C_CPU1_SB_DQS_DP<4>
J 0
(-5840 4610);
DISPLAY 0.659574 (-5840 4610);
PAINT MONO (-5840 4610);
DISPLAY INVISIBLE (-5840 4610);
FORCEPROP 1 LASTPIN (-5850 4600) BN 4
J 2
(-5838 4608);
DISPLAY 0.489362 (-5838 4608);
PAINT GREEN (-5838 4608);
FORCEPROP 2 LAST CDS_LIB mstr_standard
J 2
(-5900 4600);
DISPLAY 0.723404 (-5900 4600);
PAINT MONO (-5900 4600);
DISPLAY INVISIBLE (-5900 4600);
FORCEPROP 1 LAST BODY_TYPE PLUMBING
J 2
(-5900 4650);
DISPLAY 0.872340 (-5900 4650);
PAINT GREEN (-5900 4650);
DISPLAY INVISIBLE (-5900 4650);
FORCEPROP 1 LAST HDL_TAP TRUE
J 2
(-6225 4475);
DISPLAY 0.872340 (-6225 4475);
DISPLAY INVISIBLE (-6225 4475);
FORCEPROP 1 LAST PATH I273
J 2
(-5898 4600);
DISPLAY 0.872340 (-5898 4600);
PAINT GREEN (-5898 4600);
DISPLAY INVISIBLE (-5898 4600);
FORCEADD TAP..1
R 2
(-5900 4400);
FORCEPROP 3 LASTPIN (-5850 4400) SIG_NAME M_C_CPU1_SB_DQS_DP<6>
J 0
(-5840 4410);
DISPLAY 0.659574 (-5840 4410);
PAINT MONO (-5840 4410);
DISPLAY INVISIBLE (-5840 4410);
FORCEPROP 1 LASTPIN (-5850 4400) BN 6
J 2
(-5838 4408);
DISPLAY 0.489362 (-5838 4408);
PAINT GREEN (-5838 4408);
FORCEPROP 2 LAST CDS_LIB mstr_standard
J 2
(-5900 4400);
DISPLAY 0.723404 (-5900 4400);
PAINT MONO (-5900 4400);
DISPLAY INVISIBLE (-5900 4400);
FORCEPROP 1 LAST BODY_TYPE PLUMBING
J 2
(-5900 4450);
DISPLAY 0.872340 (-5900 4450);
PAINT GREEN (-5900 4450);
DISPLAY INVISIBLE (-5900 4450);
FORCEPROP 1 LAST HDL_TAP TRUE
J 2
(-6225 4275);
DISPLAY 0.872340 (-6225 4275);
DISPLAY INVISIBLE (-6225 4275);
FORCEPROP 1 LAST PATH I274
J 2
(-5898 4400);
DISPLAY 0.872340 (-5898 4400);
PAINT GREEN (-5898 4400);
DISPLAY INVISIBLE (-5898 4400);
FORCEADD TAP..1
R 2
(-5900 4300);
FORCEPROP 3 LASTPIN (-5850 4300) SIG_NAME M_C_CPU1_SB_DQS_DP<7>
J 0
(-5840 4310);
DISPLAY 0.659574 (-5840 4310);
PAINT MONO (-5840 4310);
DISPLAY INVISIBLE (-5840 4310);
FORCEPROP 1 LASTPIN (-5850 4300) BN 7
J 2
(-5838 4308);
DISPLAY 0.489362 (-5838 4308);
PAINT GREEN (-5838 4308);
FORCEPROP 2 LAST CDS_LIB mstr_standard
J 2
(-5900 4300);
DISPLAY 0.723404 (-5900 4300);
PAINT MONO (-5900 4300);
DISPLAY INVISIBLE (-5900 4300);
FORCEPROP 1 LAST BODY_TYPE PLUMBING
J 2
(-5900 4350);
DISPLAY 0.872340 (-5900 4350);
PAINT GREEN (-5900 4350);
DISPLAY INVISIBLE (-5900 4350);
FORCEPROP 1 LAST HDL_TAP TRUE
J 2
(-6225 4175);
DISPLAY 0.872340 (-6225 4175);
DISPLAY INVISIBLE (-6225 4175);
FORCEPROP 1 LAST PATH I275
J 2
(-5898 4300);
DISPLAY 0.872340 (-5898 4300);
PAINT GREEN (-5898 4300);
DISPLAY INVISIBLE (-5898 4300);
FORCEADD TAP..1
R 2
(-5900 4100);
FORCEPROP 3 LASTPIN (-5850 4100) SIG_NAME M_C_CPU1_SB_DQS_DP<9>
J 0
(-5840 4110);
DISPLAY 0.659574 (-5840 4110);
PAINT MONO (-5840 4110);
DISPLAY INVISIBLE (-5840 4110);
FORCEPROP 1 LASTPIN (-5850 4100) BN 9
J 2
(-5838 4108);
DISPLAY 0.489362 (-5838 4108);
PAINT GREEN (-5838 4108);
FORCEPROP 2 LAST CDS_LIB mstr_standard
J 2
(-5900 4100);
DISPLAY 0.723404 (-5900 4100);
PAINT MONO (-5900 4100);
DISPLAY INVISIBLE (-5900 4100);
FORCEPROP 1 LAST BODY_TYPE PLUMBING
J 2
(-5900 4150);
DISPLAY 0.872340 (-5900 4150);
PAINT GREEN (-5900 4150);
DISPLAY INVISIBLE (-5900 4150);
FORCEPROP 1 LAST HDL_TAP TRUE
J 2
(-6225 3975);
DISPLAY 0.872340 (-6225 3975);
DISPLAY INVISIBLE (-6225 3975);
FORCEPROP 1 LAST PATH I276
J 2
(-5898 4100);
DISPLAY 0.872340 (-5898 4100);
PAINT GREEN (-5898 4100);
DISPLAY INVISIBLE (-5898 4100);
FORCEADD TAP..1
R 2
(-5900 4200);
FORCEPROP 3 LASTPIN (-5850 4200) SIG_NAME M_C_CPU1_SB_DQS_DP<8>
J 0
(-5840 4210);
DISPLAY 0.659574 (-5840 4210);
PAINT MONO (-5840 4210);
DISPLAY INVISIBLE (-5840 4210);
FORCEPROP 1 LASTPIN (-5850 4200) BN 8
J 2
(-5838 4208);
DISPLAY 0.489362 (-5838 4208);
PAINT GREEN (-5838 4208);
FORCEPROP 2 LAST CDS_LIB mstr_standard
J 2
(-5900 4200);
DISPLAY 0.723404 (-5900 4200);
PAINT MONO (-5900 4200);
DISPLAY INVISIBLE (-5900 4200);
FORCEPROP 1 LAST BODY_TYPE PLUMBING
J 2
(-5900 4250);
DISPLAY 0.872340 (-5900 4250);
PAINT GREEN (-5900 4250);
DISPLAY INVISIBLE (-5900 4250);
FORCEPROP 1 LAST HDL_TAP TRUE
J 2
(-6225 4075);
DISPLAY 0.872340 (-6225 4075);
DISPLAY INVISIBLE (-6225 4075);
FORCEPROP 1 LAST PATH I277
J 2
(-5898 4200);
DISPLAY 0.872340 (-5898 4200);
PAINT GREEN (-5898 4200);
DISPLAY INVISIBLE (-5898 4200);
FORCEADD TAP..1
R 2
(-6100 4450);
FORCEPROP 3 LASTPIN (-6050 4450) SIG_NAME M_C_CPU1_SB_DQS_DN<5>
J 0
(-6040 4460);
DISPLAY 0.659574 (-6040 4460);
PAINT MONO (-6040 4460);
DISPLAY INVISIBLE (-6040 4460);
FORCEPROP 1 LASTPIN (-6050 4450) BN 5
J 2
(-6038 4458);
DISPLAY 0.489362 (-6038 4458);
PAINT GREEN (-6038 4458);
FORCEPROP 2 LAST CDS_LIB mstr_standard
J 2
(-6100 4450);
DISPLAY 0.723404 (-6100 4450);
PAINT MONO (-6100 4450);
DISPLAY INVISIBLE (-6100 4450);
FORCEPROP 1 LAST BODY_TYPE PLUMBING
J 2
(-6100 4500);
DISPLAY 0.872340 (-6100 4500);
PAINT GREEN (-6100 4500);
DISPLAY INVISIBLE (-6100 4500);
FORCEPROP 1 LAST HDL_TAP TRUE
J 2
(-6425 4325);
DISPLAY 0.872340 (-6425 4325);
DISPLAY INVISIBLE (-6425 4325);
FORCEPROP 1 LAST PATH I278
J 2
(-6098 4450);
DISPLAY 0.872340 (-6098 4450);
PAINT GREEN (-6098 4450);
DISPLAY INVISIBLE (-6098 4450);
FORCEADD TAP..1
R 2
(-6100 4550);
FORCEPROP 3 LASTPIN (-6050 4550) SIG_NAME M_C_CPU1_SB_DQS_DN<4>
J 0
(-6040 4560);
DISPLAY 0.659574 (-6040 4560);
PAINT MONO (-6040 4560);
DISPLAY INVISIBLE (-6040 4560);
FORCEPROP 1 LASTPIN (-6050 4550) BN 4
J 2
(-6038 4558);
DISPLAY 0.489362 (-6038 4558);
PAINT GREEN (-6038 4558);
FORCEPROP 2 LAST CDS_LIB mstr_standard
J 2
(-6100 4550);
DISPLAY 0.723404 (-6100 4550);
PAINT MONO (-6100 4550);
DISPLAY INVISIBLE (-6100 4550);
FORCEPROP 1 LAST BODY_TYPE PLUMBING
J 2
(-6100 4600);
DISPLAY 0.872340 (-6100 4600);
PAINT GREEN (-6100 4600);
DISPLAY INVISIBLE (-6100 4600);
FORCEPROP 1 LAST HDL_TAP TRUE
J 2
(-6425 4425);
DISPLAY 0.872340 (-6425 4425);
DISPLAY INVISIBLE (-6425 4425);
FORCEPROP 1 LAST PATH I279
J 2
(-6098 4550);
DISPLAY 0.872340 (-6098 4550);
PAINT GREEN (-6098 4550);
DISPLAY INVISIBLE (-6098 4550);
FORCEADD TAP..1
R 2
(-6100 4350);
FORCEPROP 3 LASTPIN (-6050 4350) SIG_NAME M_C_CPU1_SB_DQS_DN<6>
J 0
(-6040 4360);
DISPLAY 0.659574 (-6040 4360);
PAINT MONO (-6040 4360);
DISPLAY INVISIBLE (-6040 4360);
FORCEPROP 1 LASTPIN (-6050 4350) BN 6
J 2
(-6038 4358);
DISPLAY 0.489362 (-6038 4358);
PAINT GREEN (-6038 4358);
FORCEPROP 2 LAST CDS_LIB mstr_standard
J 2
(-6100 4350);
DISPLAY 0.723404 (-6100 4350);
PAINT MONO (-6100 4350);
DISPLAY INVISIBLE (-6100 4350);
FORCEPROP 1 LAST BODY_TYPE PLUMBING
J 2
(-6100 4400);
DISPLAY 0.872340 (-6100 4400);
PAINT GREEN (-6100 4400);
DISPLAY INVISIBLE (-6100 4400);
FORCEPROP 1 LAST HDL_TAP TRUE
J 2
(-6425 4225);
DISPLAY 0.872340 (-6425 4225);
DISPLAY INVISIBLE (-6425 4225);
FORCEPROP 1 LAST PATH I280
J 2
(-6098 4350);
DISPLAY 0.872340 (-6098 4350);
PAINT GREEN (-6098 4350);
DISPLAY INVISIBLE (-6098 4350);
FORCEADD TAP..1
R 2
(-6100 4250);
FORCEPROP 3 LASTPIN (-6050 4250) SIG_NAME M_C_CPU1_SB_DQS_DN<7>
J 0
(-6040 4260);
DISPLAY 0.659574 (-6040 4260);
PAINT MONO (-6040 4260);
DISPLAY INVISIBLE (-6040 4260);
FORCEPROP 1 LASTPIN (-6050 4250) BN 7
J 2
(-6038 4258);
DISPLAY 0.489362 (-6038 4258);
PAINT GREEN (-6038 4258);
FORCEPROP 2 LAST CDS_LIB mstr_standard
J 2
(-6100 4250);
DISPLAY 0.723404 (-6100 4250);
PAINT MONO (-6100 4250);
DISPLAY INVISIBLE (-6100 4250);
FORCEPROP 1 LAST BODY_TYPE PLUMBING
J 2
(-6100 4300);
DISPLAY 0.872340 (-6100 4300);
PAINT GREEN (-6100 4300);
DISPLAY INVISIBLE (-6100 4300);
FORCEPROP 1 LAST HDL_TAP TRUE
J 2
(-6425 4125);
DISPLAY 0.872340 (-6425 4125);
DISPLAY INVISIBLE (-6425 4125);
FORCEPROP 1 LAST PATH I281
J 2
(-6098 4250);
DISPLAY 0.872340 (-6098 4250);
PAINT GREEN (-6098 4250);
DISPLAY INVISIBLE (-6098 4250);
FORCEADD TAP..1
R 2
(-6100 4150);
FORCEPROP 3 LASTPIN (-6050 4150) SIG_NAME M_C_CPU1_SB_DQS_DN<8>
J 0
(-6040 4160);
DISPLAY 0.659574 (-6040 4160);
PAINT MONO (-6040 4160);
DISPLAY INVISIBLE (-6040 4160);
FORCEPROP 1 LASTPIN (-6050 4150) BN 8
J 2
(-6038 4158);
DISPLAY 0.489362 (-6038 4158);
PAINT GREEN (-6038 4158);
FORCEPROP 2 LAST CDS_LIB mstr_standard
J 2
(-6100 4150);
DISPLAY 0.723404 (-6100 4150);
PAINT MONO (-6100 4150);
DISPLAY INVISIBLE (-6100 4150);
FORCEPROP 1 LAST BODY_TYPE PLUMBING
J 2
(-6100 4200);
DISPLAY 0.872340 (-6100 4200);
PAINT GREEN (-6100 4200);
DISPLAY INVISIBLE (-6100 4200);
FORCEPROP 1 LAST HDL_TAP TRUE
J 2
(-6425 4025);
DISPLAY 0.872340 (-6425 4025);
DISPLAY INVISIBLE (-6425 4025);
FORCEPROP 1 LAST PATH I282
J 2
(-6098 4150);
DISPLAY 0.872340 (-6098 4150);
PAINT GREEN (-6098 4150);
DISPLAY INVISIBLE (-6098 4150);
FORCEADD OFFPAGE..3
R 2
(-6800 6025);
FORCEPROP 2 LAST $XR0 100 
J 0
(-7110 6025);
DISPLAY 0.638298 (-7110 6025);
PAINT MONO (-7110 6025);
FORCEPROP 2 LAST CDS_LIB standard
J 0
(-6800 6025);
DISPLAY INVISIBLE (-6800 6025);
FORCEPROP 1 LAST OFFPAGE TRUE
J 2
(-7125 5900);
DISPLAY 0.872340 (-7125 5900);
PAINT GREEN (-7125 5900);
DISPLAY INVISIBLE (-7125 5900);
FORCEPROP 1 LAST COMMENT_BODY TRUE
J 2
(-6750 5925);
DISPLAY 0.872340 (-6750 5925);
PAINT GREEN (-6750 5925);
DISPLAY INVISIBLE (-6750 5925);
FORCEPROP 2 LAST PATH I283
J 0
(-7100 6075);
DISPLAY 1.021277 (-7100 6075);
DISPLAY INVISIBLE (-7100 6075);
FORCEADD OFFPAGE..3
R 2
(-6800 6075);
FORCEPROP 2 LAST $XR0 100 
J 0
(-7110 6075);
DISPLAY 0.638298 (-7110 6075);
PAINT MONO (-7110 6075);
FORCEPROP 2 LAST CDS_LIB standard
J 0
(-6800 6075);
DISPLAY INVISIBLE (-6800 6075);
FORCEPROP 1 LAST OFFPAGE TRUE
J 2
(-7125 5950);
DISPLAY 0.872340 (-7125 5950);
PAINT GREEN (-7125 5950);
DISPLAY INVISIBLE (-7125 5950);
FORCEPROP 1 LAST COMMENT_BODY TRUE
J 2
(-6750 5975);
DISPLAY 0.872340 (-6750 5975);
PAINT GREEN (-6750 5975);
DISPLAY INVISIBLE (-6750 5975);
FORCEPROP 2 LAST PATH I284
J 0
(-7100 6125);
DISPLAY 1.021277 (-7100 6125);
DISPLAY INVISIBLE (-7100 6125);
FORCEADD OFFPAGE..3
R 2
(-6800 4975);
FORCEPROP 2 LAST $XR0 100 
J 0
(-7110 4975);
DISPLAY 0.638298 (-7110 4975);
PAINT MONO (-7110 4975);
FORCEPROP 2 LAST CDS_LIB standard
J 0
(-6800 4975);
DISPLAY INVISIBLE (-6800 4975);
FORCEPROP 1 LAST OFFPAGE TRUE
J 2
(-7125 4850);
DISPLAY 0.872340 (-7125 4850);
PAINT GREEN (-7125 4850);
DISPLAY INVISIBLE (-7125 4850);
FORCEPROP 1 LAST COMMENT_BODY TRUE
J 2
(-6750 4875);
DISPLAY 0.872340 (-6750 4875);
PAINT GREEN (-6750 4875);
DISPLAY INVISIBLE (-6750 4875);
FORCEPROP 2 LAST PATH I285
J 0
(-7100 5025);
DISPLAY 1.021277 (-7100 5025);
DISPLAY INVISIBLE (-7100 5025);
FORCEADD OFFPAGE..3
R 2
(-6800 5025);
FORCEPROP 2 LAST $XR0 100 
J 0
(-7110 5025);
DISPLAY 0.638298 (-7110 5025);
PAINT MONO (-7110 5025);
FORCEPROP 2 LAST CDS_LIB standard
J 0
(-6800 5025);
DISPLAY INVISIBLE (-6800 5025);
FORCEPROP 1 LAST OFFPAGE TRUE
J 2
(-7125 4900);
DISPLAY 0.872340 (-7125 4900);
PAINT GREEN (-7125 4900);
DISPLAY INVISIBLE (-7125 4900);
FORCEPROP 1 LAST COMMENT_BODY TRUE
J 2
(-6750 4925);
DISPLAY 0.872340 (-6750 4925);
PAINT GREEN (-6750 4925);
DISPLAY INVISIBLE (-6750 4925);
FORCEPROP 2 LAST PATH I286
J 0
(-7100 5075);
DISPLAY 1.021277 (-7100 5075);
DISPLAY INVISIBLE (-7100 5075);
FORCEADD TAP..1
R 2
(-6100 4050);
FORCEPROP 3 LASTPIN (-6050 4050) SIG_NAME M_C_CPU1_SB_DQS_DN<9>
J 0
(-6040 4060);
DISPLAY 0.659574 (-6040 4060);
PAINT MONO (-6040 4060);
DISPLAY INVISIBLE (-6040 4060);
FORCEPROP 1 LASTPIN (-6050 4050) BN 9
J 2
(-6038 4058);
DISPLAY 0.489362 (-6038 4058);
PAINT GREEN (-6038 4058);
FORCEPROP 2 LAST CDS_LIB mstr_standard
J 2
(-6100 4050);
DISPLAY 0.723404 (-6100 4050);
PAINT MONO (-6100 4050);
DISPLAY INVISIBLE (-6100 4050);
FORCEPROP 1 LAST BODY_TYPE PLUMBING
J 2
(-6100 4100);
DISPLAY 0.872340 (-6100 4100);
PAINT GREEN (-6100 4100);
DISPLAY INVISIBLE (-6100 4100);
FORCEPROP 1 LAST HDL_TAP TRUE
J 2
(-6425 3925);
DISPLAY 0.872340 (-6425 3925);
DISPLAY INVISIBLE (-6425 3925);
FORCEPROP 1 LAST PATH I287
J 2
(-6098 4050);
DISPLAY 0.872340 (-6098 4050);
PAINT GREEN (-6098 4050);
DISPLAY INVISIBLE (-6098 4050);
FORCEADD TAP..1
R 2
(-6100 3850);
FORCEPROP 3 LASTPIN (-6050 3850) SIG_NAME M_C_CPU1_SA_CA<1>
J 0
(-6040 3860);
DISPLAY 0.659574 (-6040 3860);
PAINT MONO (-6040 3860);
DISPLAY INVISIBLE (-6040 3860);
FORCEPROP 1 LASTPIN (-6050 3850) BN 1
J 2
(-6038 3858);
DISPLAY 0.489362 (-6038 3858);
PAINT GREEN (-6038 3858);
FORCEPROP 2 LAST CDS_LIB mstr_standard
J 0
(-6100 3850);
DISPLAY 0.723404 (-6100 3850);
PAINT MONO (-6100 3850);
DISPLAY INVISIBLE (-6100 3850);
FORCEPROP 1 LAST BODY_TYPE PLUMBING
J 2
(-6100 3900);
DISPLAY 0.872340 (-6100 3900);
PAINT GREEN (-6100 3900);
DISPLAY INVISIBLE (-6100 3900);
FORCEPROP 1 LAST HDL_TAP TRUE
J 2
(-6425 3725);
DISPLAY 0.872340 (-6425 3725);
DISPLAY INVISIBLE (-6425 3725);
FORCEPROP 1 LAST PATH I288
J 2
(-6098 3850);
DISPLAY 0.872340 (-6098 3850);
PAINT GREEN (-6098 3850);
DISPLAY INVISIBLE (-6098 3850);
FORCEADD TAP..1
R 2
(-6100 3900);
FORCEPROP 3 LASTPIN (-6050 3900) SIG_NAME M_C_CPU1_SA_CA<0>
J 0
(-6040 3910);
DISPLAY 0.659574 (-6040 3910);
PAINT MONO (-6040 3910);
DISPLAY INVISIBLE (-6040 3910);
FORCEPROP 1 LASTPIN (-6050 3900) BN 0
J 2
(-6038 3908);
DISPLAY 0.489362 (-6038 3908);
PAINT GREEN (-6038 3908);
FORCEPROP 2 LAST CDS_LIB mstr_standard
J 0
(-6100 3900);
DISPLAY 0.723404 (-6100 3900);
PAINT MONO (-6100 3900);
DISPLAY INVISIBLE (-6100 3900);
FORCEPROP 1 LAST BODY_TYPE PLUMBING
J 2
(-6100 3950);
DISPLAY 0.872340 (-6100 3950);
PAINT GREEN (-6100 3950);
DISPLAY INVISIBLE (-6100 3950);
FORCEPROP 1 LAST HDL_TAP TRUE
J 2
(-6425 3775);
DISPLAY 0.872340 (-6425 3775);
DISPLAY INVISIBLE (-6425 3775);
FORCEPROP 1 LAST PATH I289
J 2
(-6098 3900);
DISPLAY 0.872340 (-6098 3900);
PAINT GREEN (-6098 3900);
DISPLAY INVISIBLE (-6098 3900);
FORCEADD TAP..1
R 2
(-6100 3750);
FORCEPROP 3 LASTPIN (-6050 3750) SIG_NAME M_C_CPU1_SA_CA<3>
J 0
(-6040 3760);
DISPLAY 0.659574 (-6040 3760);
PAINT MONO (-6040 3760);
DISPLAY INVISIBLE (-6040 3760);
FORCEPROP 1 LASTPIN (-6050 3750) BN 3
J 2
(-6038 3758);
DISPLAY 0.489362 (-6038 3758);
PAINT GREEN (-6038 3758);
FORCEPROP 2 LAST CDS_LIB mstr_standard
J 0
(-6100 3750);
DISPLAY 0.723404 (-6100 3750);
PAINT MONO (-6100 3750);
DISPLAY INVISIBLE (-6100 3750);
FORCEPROP 1 LAST BODY_TYPE PLUMBING
J 2
(-6100 3800);
DISPLAY 0.872340 (-6100 3800);
PAINT GREEN (-6100 3800);
DISPLAY INVISIBLE (-6100 3800);
FORCEPROP 1 LAST HDL_TAP TRUE
J 2
(-6425 3625);
DISPLAY 0.872340 (-6425 3625);
DISPLAY INVISIBLE (-6425 3625);
FORCEPROP 1 LAST PATH I290
J 2
(-6098 3750);
DISPLAY 0.872340 (-6098 3750);
PAINT GREEN (-6098 3750);
DISPLAY INVISIBLE (-6098 3750);
FORCEADD TAP..1
R 2
(-6100 3800);
FORCEPROP 3 LASTPIN (-6050 3800) SIG_NAME M_C_CPU1_SA_CA<2>
J 0
(-6040 3810);
DISPLAY 0.659574 (-6040 3810);
PAINT MONO (-6040 3810);
DISPLAY INVISIBLE (-6040 3810);
FORCEPROP 1 LASTPIN (-6050 3800) BN 2
J 2
(-6038 3808);
DISPLAY 0.489362 (-6038 3808);
PAINT GREEN (-6038 3808);
FORCEPROP 2 LAST CDS_LIB mstr_standard
J 0
(-6100 3800);
DISPLAY 0.723404 (-6100 3800);
PAINT MONO (-6100 3800);
DISPLAY INVISIBLE (-6100 3800);
FORCEPROP 1 LAST BODY_TYPE PLUMBING
J 2
(-6100 3850);
DISPLAY 0.872340 (-6100 3850);
PAINT GREEN (-6100 3850);
DISPLAY INVISIBLE (-6100 3850);
FORCEPROP 1 LAST HDL_TAP TRUE
J 2
(-6425 3675);
DISPLAY 0.872340 (-6425 3675);
DISPLAY INVISIBLE (-6425 3675);
FORCEPROP 1 LAST PATH I291
J 2
(-6098 3800);
DISPLAY 0.872340 (-6098 3800);
PAINT GREEN (-6098 3800);
DISPLAY INVISIBLE (-6098 3800);
FORCEADD TAP..1
R 2
(-6100 3700);
FORCEPROP 3 LASTPIN (-6050 3700) SIG_NAME M_C_CPU1_SA_CA<4>
J 0
(-6040 3710);
DISPLAY 0.659574 (-6040 3710);
PAINT MONO (-6040 3710);
DISPLAY INVISIBLE (-6040 3710);
FORCEPROP 1 LASTPIN (-6050 3700) BN 4
J 2
(-6038 3708);
DISPLAY 0.489362 (-6038 3708);
PAINT GREEN (-6038 3708);
FORCEPROP 2 LAST CDS_LIB mstr_standard
J 0
(-6100 3700);
DISPLAY 0.723404 (-6100 3700);
PAINT MONO (-6100 3700);
DISPLAY INVISIBLE (-6100 3700);
FORCEPROP 1 LAST BODY_TYPE PLUMBING
J 2
(-6100 3750);
DISPLAY 0.872340 (-6100 3750);
PAINT GREEN (-6100 3750);
DISPLAY INVISIBLE (-6100 3750);
FORCEPROP 1 LAST HDL_TAP TRUE
J 2
(-6425 3575);
DISPLAY 0.872340 (-6425 3575);
DISPLAY INVISIBLE (-6425 3575);
FORCEPROP 1 LAST PATH I292
J 2
(-6098 3700);
DISPLAY 0.872340 (-6098 3700);
PAINT GREEN (-6098 3700);
DISPLAY INVISIBLE (-6098 3700);
FORCEADD TAP..1
R 2
(-6100 3650);
FORCEPROP 3 LASTPIN (-6050 3650) SIG_NAME M_C_CPU1_SA_CA<5>
J 0
(-6040 3660);
DISPLAY 0.659574 (-6040 3660);
PAINT MONO (-6040 3660);
DISPLAY INVISIBLE (-6040 3660);
FORCEPROP 1 LASTPIN (-6050 3650) BN 5
J 2
(-6038 3658);
DISPLAY 0.489362 (-6038 3658);
PAINT GREEN (-6038 3658);
FORCEPROP 2 LAST CDS_LIB mstr_standard
J 0
(-6100 3650);
DISPLAY 0.723404 (-6100 3650);
PAINT MONO (-6100 3650);
DISPLAY INVISIBLE (-6100 3650);
FORCEPROP 1 LAST BODY_TYPE PLUMBING
J 2
(-6100 3700);
DISPLAY 0.872340 (-6100 3700);
PAINT GREEN (-6100 3700);
DISPLAY INVISIBLE (-6100 3700);
FORCEPROP 1 LAST HDL_TAP TRUE
J 2
(-6425 3525);
DISPLAY 0.872340 (-6425 3525);
DISPLAY INVISIBLE (-6425 3525);
FORCEPROP 1 LAST PATH I293
J 2
(-6098 3650);
DISPLAY 0.872340 (-6098 3650);
PAINT GREEN (-6098 3650);
DISPLAY INVISIBLE (-6098 3650);
FORCEADD TAP..1
R 2
(-6100 3600);
FORCEPROP 3 LASTPIN (-6050 3600) SIG_NAME M_C_CPU1_SA_CA<6>
J 0
(-6040 3610);
DISPLAY 0.659574 (-6040 3610);
PAINT MONO (-6040 3610);
DISPLAY INVISIBLE (-6040 3610);
FORCEPROP 1 LASTPIN (-6050 3600) BN 6
J 2
(-6038 3608);
DISPLAY 0.489362 (-6038 3608);
PAINT GREEN (-6038 3608);
FORCEPROP 2 LAST CDS_LIB mstr_standard
J 0
(-6100 3600);
DISPLAY 0.723404 (-6100 3600);
PAINT MONO (-6100 3600);
DISPLAY INVISIBLE (-6100 3600);
FORCEPROP 1 LAST BODY_TYPE PLUMBING
J 2
(-6100 3650);
DISPLAY 0.872340 (-6100 3650);
PAINT GREEN (-6100 3650);
DISPLAY INVISIBLE (-6100 3650);
FORCEPROP 1 LAST HDL_TAP TRUE
J 2
(-6425 3475);
DISPLAY 0.872340 (-6425 3475);
DISPLAY INVISIBLE (-6425 3475);
FORCEPROP 1 LAST PATH I294
J 2
(-6098 3600);
DISPLAY 0.872340 (-6098 3600);
PAINT GREEN (-6098 3600);
DISPLAY INVISIBLE (-6098 3600);
FORCEADD TAP..1
R 2
(-6100 3400);
FORCEPROP 3 LASTPIN (-6050 3400) SIG_NAME M_C_CPU1_SB_CA<2>
J 0
(-6040 3410);
DISPLAY 0.659574 (-6040 3410);
PAINT MONO (-6040 3410);
DISPLAY INVISIBLE (-6040 3410);
FORCEPROP 1 LASTPIN (-6050 3400) BN 2
J 2
(-6038 3408);
DISPLAY 0.489362 (-6038 3408);
PAINT GREEN (-6038 3408);
FORCEPROP 2 LAST CDS_LIB mstr_standard
J 0
(-6100 3400);
DISPLAY 0.723404 (-6100 3400);
PAINT MONO (-6100 3400);
DISPLAY INVISIBLE (-6100 3400);
FORCEPROP 1 LAST BODY_TYPE PLUMBING
J 2
(-6100 3450);
DISPLAY 0.872340 (-6100 3450);
PAINT GREEN (-6100 3450);
DISPLAY INVISIBLE (-6100 3450);
FORCEPROP 1 LAST HDL_TAP TRUE
J 2
(-6425 3275);
DISPLAY 0.872340 (-6425 3275);
DISPLAY INVISIBLE (-6425 3275);
FORCEPROP 1 LAST PATH I295
J 2
(-6098 3400);
DISPLAY 0.872340 (-6098 3400);
PAINT GREEN (-6098 3400);
DISPLAY INVISIBLE (-6098 3400);
FORCEADD TAP..1
R 2
(-6100 3450);
FORCEPROP 3 LASTPIN (-6050 3450) SIG_NAME M_C_CPU1_SB_CA<1>
J 0
(-6040 3460);
DISPLAY 0.659574 (-6040 3460);
PAINT MONO (-6040 3460);
DISPLAY INVISIBLE (-6040 3460);
FORCEPROP 1 LASTPIN (-6050 3450) BN 1
J 2
(-6038 3458);
DISPLAY 0.489362 (-6038 3458);
PAINT GREEN (-6038 3458);
FORCEPROP 2 LAST CDS_LIB mstr_standard
J 0
(-6100 3450);
DISPLAY 0.723404 (-6100 3450);
PAINT MONO (-6100 3450);
DISPLAY INVISIBLE (-6100 3450);
FORCEPROP 1 LAST BODY_TYPE PLUMBING
J 2
(-6100 3500);
DISPLAY 0.872340 (-6100 3500);
PAINT GREEN (-6100 3500);
DISPLAY INVISIBLE (-6100 3500);
FORCEPROP 1 LAST HDL_TAP TRUE
J 2
(-6425 3325);
DISPLAY 0.872340 (-6425 3325);
DISPLAY INVISIBLE (-6425 3325);
FORCEPROP 1 LAST PATH I296
J 2
(-6098 3450);
DISPLAY 0.872340 (-6098 3450);
PAINT GREEN (-6098 3450);
DISPLAY INVISIBLE (-6098 3450);
FORCEADD TAP..1
R 2
(-6100 3500);
FORCEPROP 3 LASTPIN (-6050 3500) SIG_NAME M_C_CPU1_SB_CA<0>
J 0
(-6040 3510);
DISPLAY 0.659574 (-6040 3510);
PAINT MONO (-6040 3510);
DISPLAY INVISIBLE (-6040 3510);
FORCEPROP 1 LASTPIN (-6050 3500) BN 0
J 2
(-6038 3508);
DISPLAY 0.489362 (-6038 3508);
PAINT GREEN (-6038 3508);
FORCEPROP 2 LAST CDS_LIB mstr_standard
J 0
(-6100 3500);
DISPLAY 0.723404 (-6100 3500);
PAINT MONO (-6100 3500);
DISPLAY INVISIBLE (-6100 3500);
FORCEPROP 1 LAST BODY_TYPE PLUMBING
J 2
(-6100 3550);
DISPLAY 0.872340 (-6100 3550);
PAINT GREEN (-6100 3550);
DISPLAY INVISIBLE (-6100 3550);
FORCEPROP 1 LAST HDL_TAP TRUE
J 2
(-6425 3375);
DISPLAY 0.872340 (-6425 3375);
DISPLAY INVISIBLE (-6425 3375);
FORCEPROP 1 LAST PATH I297
J 2
(-6098 3500);
DISPLAY 0.872340 (-6098 3500);
PAINT GREEN (-6098 3500);
DISPLAY INVISIBLE (-6098 3500);
FORCEADD TAP..1
R 2
(-6100 3350);
FORCEPROP 3 LASTPIN (-6050 3350) SIG_NAME M_C_CPU1_SB_CA<3>
J 0
(-6040 3360);
DISPLAY 0.659574 (-6040 3360);
PAINT MONO (-6040 3360);
DISPLAY INVISIBLE (-6040 3360);
FORCEPROP 1 LASTPIN (-6050 3350) BN 3
J 2
(-6038 3358);
DISPLAY 0.489362 (-6038 3358);
PAINT GREEN (-6038 3358);
FORCEPROP 2 LAST CDS_LIB mstr_standard
J 0
(-6100 3350);
DISPLAY 0.723404 (-6100 3350);
PAINT MONO (-6100 3350);
DISPLAY INVISIBLE (-6100 3350);
FORCEPROP 1 LAST BODY_TYPE PLUMBING
J 2
(-6100 3400);
DISPLAY 0.872340 (-6100 3400);
PAINT GREEN (-6100 3400);
DISPLAY INVISIBLE (-6100 3400);
FORCEPROP 1 LAST HDL_TAP TRUE
J 2
(-6425 3225);
DISPLAY 0.872340 (-6425 3225);
DISPLAY INVISIBLE (-6425 3225);
FORCEPROP 1 LAST PATH I298
J 2
(-6098 3350);
DISPLAY 0.872340 (-6098 3350);
PAINT GREEN (-6098 3350);
DISPLAY INVISIBLE (-6098 3350);
FORCEADD TAP..1
R 2
(-6100 3300);
FORCEPROP 3 LASTPIN (-6050 3300) SIG_NAME M_C_CPU1_SB_CA<4>
J 0
(-6040 3310);
DISPLAY 0.659574 (-6040 3310);
PAINT MONO (-6040 3310);
DISPLAY INVISIBLE (-6040 3310);
FORCEPROP 1 LASTPIN (-6050 3300) BN 4
J 2
(-6038 3308);
DISPLAY 0.489362 (-6038 3308);
PAINT GREEN (-6038 3308);
FORCEPROP 2 LAST CDS_LIB mstr_standard
J 0
(-6100 3300);
DISPLAY 0.723404 (-6100 3300);
PAINT MONO (-6100 3300);
DISPLAY INVISIBLE (-6100 3300);
FORCEPROP 1 LAST BODY_TYPE PLUMBING
J 2
(-6100 3350);
DISPLAY 0.872340 (-6100 3350);
PAINT GREEN (-6100 3350);
DISPLAY INVISIBLE (-6100 3350);
FORCEPROP 1 LAST HDL_TAP TRUE
J 2
(-6425 3175);
DISPLAY 0.872340 (-6425 3175);
DISPLAY INVISIBLE (-6425 3175);
FORCEPROP 1 LAST PATH I299
J 2
(-6098 3300);
DISPLAY 0.872340 (-6098 3300);
PAINT GREEN (-6098 3300);
DISPLAY INVISIBLE (-6098 3300);
FORCEADD TAP..1
R 2
(-6100 3250);
FORCEPROP 3 LASTPIN (-6050 3250) SIG_NAME M_C_CPU1_SB_CA<5>
J 0
(-6040 3260);
DISPLAY 0.659574 (-6040 3260);
PAINT MONO (-6040 3260);
DISPLAY INVISIBLE (-6040 3260);
FORCEPROP 1 LASTPIN (-6050 3250) BN 5
J 2
(-6038 3258);
DISPLAY 0.489362 (-6038 3258);
PAINT GREEN (-6038 3258);
FORCEPROP 2 LAST CDS_LIB mstr_standard
J 0
(-6100 3250);
DISPLAY 0.723404 (-6100 3250);
PAINT MONO (-6100 3250);
DISPLAY INVISIBLE (-6100 3250);
FORCEPROP 1 LAST BODY_TYPE PLUMBING
J 2
(-6100 3300);
DISPLAY 0.872340 (-6100 3300);
PAINT GREEN (-6100 3300);
DISPLAY INVISIBLE (-6100 3300);
FORCEPROP 1 LAST HDL_TAP TRUE
J 2
(-6425 3125);
DISPLAY 0.872340 (-6425 3125);
DISPLAY INVISIBLE (-6425 3125);
FORCEPROP 1 LAST PATH I300
J 2
(-6098 3250);
DISPLAY 0.872340 (-6098 3250);
PAINT GREEN (-6098 3250);
DISPLAY INVISIBLE (-6098 3250);
FORCEADD TAP..1
R 2
(-6100 3200);
FORCEPROP 3 LASTPIN (-6050 3200) SIG_NAME M_C_CPU1_SB_CA<6>
J 0
(-6040 3210);
DISPLAY 0.659574 (-6040 3210);
PAINT MONO (-6040 3210);
DISPLAY INVISIBLE (-6040 3210);
FORCEPROP 1 LASTPIN (-6050 3200) BN 6
J 2
(-6038 3208);
DISPLAY 0.489362 (-6038 3208);
PAINT GREEN (-6038 3208);
FORCEPROP 2 LAST CDS_LIB mstr_standard
J 0
(-6100 3200);
DISPLAY 0.723404 (-6100 3200);
PAINT MONO (-6100 3200);
DISPLAY INVISIBLE (-6100 3200);
FORCEPROP 1 LAST BODY_TYPE PLUMBING
J 2
(-6100 3250);
DISPLAY 0.872340 (-6100 3250);
PAINT GREEN (-6100 3250);
DISPLAY INVISIBLE (-6100 3250);
FORCEPROP 1 LAST HDL_TAP TRUE
J 2
(-6425 3075);
DISPLAY 0.872340 (-6425 3075);
DISPLAY INVISIBLE (-6425 3075);
FORCEPROP 1 LAST PATH I301
J 2
(-6098 3200);
DISPLAY 0.872340 (-6098 3200);
PAINT GREEN (-6098 3200);
DISPLAY INVISIBLE (-6098 3200);
FORCEADD OFFPAGE..2
R 2
(-6700 3925);
FORCEPROP 2 LAST $XR0 100 
J 0
(-6985 3925);
DISPLAY 0.638298 (-6985 3925);
PAINT MONO (-6985 3925);
FORCEPROP 2 LAST CDS_LIB standard
J 0
(-6700 3925);
DISPLAY INVISIBLE (-6700 3925);
FORCEPROP 1 LAST OFFPAGE TRUE
J 2
(-7025 3800);
DISPLAY 0.872340 (-7025 3800);
PAINT GREEN (-7025 3800);
DISPLAY INVISIBLE (-7025 3800);
FORCEPROP 1 LAST COMMENT_BODY TRUE
J 2
(-6655 3830);
DISPLAY 0.872340 (-6655 3830);
PAINT GREEN (-6655 3830);
DISPLAY INVISIBLE (-6655 3830);
FORCEPROP 2 LAST PATH I302
J 0
(-6975 3975);
DISPLAY 1.021277 (-6975 3975);
DISPLAY INVISIBLE (-6975 3975);
FORCEADD OFFPAGE..2
R 2
(-6700 3525);
FORCEPROP 2 LAST $XR0 100 
J 0
(-6985 3525);
DISPLAY 0.638298 (-6985 3525);
PAINT MONO (-6985 3525);
FORCEPROP 2 LAST CDS_LIB standard
J 0
(-6700 3525);
DISPLAY INVISIBLE (-6700 3525);
FORCEPROP 1 LAST OFFPAGE TRUE
J 2
(-7025 3400);
DISPLAY 0.872340 (-7025 3400);
PAINT GREEN (-7025 3400);
DISPLAY INVISIBLE (-7025 3400);
FORCEPROP 1 LAST COMMENT_BODY TRUE
J 2
(-6655 3430);
DISPLAY 0.872340 (-6655 3430);
PAINT GREEN (-6655 3430);
DISPLAY INVISIBLE (-6655 3430);
FORCEPROP 2 LAST PATH I303
J 0
(-6975 3575);
DISPLAY 1.021277 (-6975 3575);
DISPLAY INVISIBLE (-6975 3575);
FORCEADD OFFPAGE..2
R 2
(-6700 3000);
FORCEPROP 2 LAST $XR0 100 
J 0
(-6985 3000);
DISPLAY 0.638298 (-6985 3000);
PAINT MONO (-6985 3000);
FORCEPROP 2 LAST CDS_LIB standard
J 0
(-6700 3000);
DISPLAY INVISIBLE (-6700 3000);
FORCEPROP 1 LAST OFFPAGE TRUE
J 2
(-7025 2875);
DISPLAY 0.872340 (-7025 2875);
PAINT GREEN (-7025 2875);
DISPLAY INVISIBLE (-7025 2875);
FORCEPROP 1 LAST COMMENT_BODY TRUE
J 2
(-6655 2905);
DISPLAY 0.872340 (-6655 2905);
PAINT GREEN (-6655 2905);
DISPLAY INVISIBLE (-6655 2905);
FORCEPROP 2 LAST PATH I304
J 0
(-6975 3050);
DISPLAY 1.021277 (-6975 3050);
DISPLAY INVISIBLE (-6975 3050);
FORCEADD OFFPAGE..2
R 2
(-6700 3050);
FORCEPROP 2 LAST $XR0 100 
J 0
(-6985 3050);
DISPLAY 0.638298 (-6985 3050);
PAINT MONO (-6985 3050);
FORCEPROP 2 LAST CDS_LIB standard
J 0
(-6700 3050);
DISPLAY INVISIBLE (-6700 3050);
FORCEPROP 1 LAST OFFPAGE TRUE
J 2
(-7025 2925);
DISPLAY 0.872340 (-7025 2925);
PAINT GREEN (-7025 2925);
DISPLAY INVISIBLE (-7025 2925);
FORCEPROP 1 LAST COMMENT_BODY TRUE
J 2
(-6655 2955);
DISPLAY 0.872340 (-6655 2955);
PAINT GREEN (-6655 2955);
DISPLAY INVISIBLE (-6655 2955);
FORCEPROP 2 LAST PATH I305
J 0
(-6975 3100);
DISPLAY 1.021277 (-6975 3100);
DISPLAY INVISIBLE (-6975 3100);
FORCEADD OFFPAGE..2
R 2
(-6700 2850);
FORCEPROP 2 LAST $XR0 100 
J 0
(-6985 2850);
DISPLAY 0.638298 (-6985 2850);
PAINT MONO (-6985 2850);
FORCEPROP 2 LAST CDS_LIB standard
J 0
(-6700 2850);
DISPLAY INVISIBLE (-6700 2850);
FORCEPROP 1 LAST OFFPAGE TRUE
J 2
(-7025 2725);
DISPLAY 0.872340 (-7025 2725);
PAINT GREEN (-7025 2725);
DISPLAY INVISIBLE (-7025 2725);
FORCEPROP 1 LAST COMMENT_BODY TRUE
J 2
(-6655 2755);
DISPLAY 0.872340 (-6655 2755);
PAINT GREEN (-6655 2755);
DISPLAY INVISIBLE (-6655 2755);
FORCEPROP 2 LAST PATH I306
J 0
(-6975 2900);
DISPLAY 1.021277 (-6975 2900);
DISPLAY INVISIBLE (-6975 2900);
FORCEADD OFFPAGE..2
R 2
(-6700 2900);
FORCEPROP 2 LAST $XR0 100 
J 0
(-6985 2900);
DISPLAY 0.638298 (-6985 2900);
PAINT MONO (-6985 2900);
FORCEPROP 2 LAST CDS_LIB standard
J 0
(-6700 2900);
DISPLAY INVISIBLE (-6700 2900);
FORCEPROP 1 LAST OFFPAGE TRUE
J 2
(-7025 2775);
DISPLAY 0.872340 (-7025 2775);
PAINT GREEN (-7025 2775);
DISPLAY INVISIBLE (-7025 2775);
FORCEPROP 1 LAST COMMENT_BODY TRUE
J 2
(-6655 2805);
DISPLAY 0.872340 (-6655 2805);
PAINT GREEN (-6655 2805);
DISPLAY INVISIBLE (-6655 2805);
FORCEPROP 2 LAST PATH I307
J 0
(-6975 2950);
DISPLAY 1.021277 (-6975 2950);
DISPLAY INVISIBLE (-6975 2950);
FORCEADD OFFPAGE..1
(-6700 2750);
FORCEPROP 2 LAST $XR0 100 
J 0
(-6952 2750);
DISPLAY 0.638298 (-6952 2750);
PAINT MONO (-6952 2750);
FORCEPROP 2 LAST CDS_LIB standard
J 0
(-6700 2750);
DISPLAY INVISIBLE (-6700 2750);
FORCEPROP 1 LAST OFFPAGE TRUE
J 0
(-6375 2625);
DISPLAY 0.872340 (-6375 2625);
PAINT GREEN (-6375 2625);
DISPLAY INVISIBLE (-6375 2625);
FORCEPROP 1 LAST COMMENT_BODY TRUE
J 0
(-6575 2650);
DISPLAY 0.872340 (-6575 2650);
PAINT GREEN (-6575 2650);
DISPLAY INVISIBLE (-6575 2650);
FORCEPROP 2 LAST PATH I308
J 0
(-6950 2800);
DISPLAY 1.021277 (-6950 2800);
DISPLAY INVISIBLE (-6950 2800);
FORCEADD OFFPAGE..5
(-6700 2650);
FORCEPROP 2 LAST $XR0 100 
J 0
(-6985 2650);
DISPLAY 0.638298 (-6985 2650);
PAINT MONO (-6985 2650);
FORCEPROP 2 LAST CDS_LIB mstr_standard
J 0
(-6700 2650);
DISPLAY INVISIBLE (-6700 2650);
FORCEPROP 1 LAST OFFPAGE TRUE
J 0
(-6375 2525);
DISPLAY 0.872340 (-6375 2525);
PAINT GREEN (-6375 2525);
DISPLAY INVISIBLE (-6375 2525);
FORCEPROP 1 LAST COMMENT_BODY TRUE
J 0
(-6600 2575);
DISPLAY 0.872340 (-6600 2575);
PAINT GREEN (-6600 2575);
DISPLAY INVISIBLE (-6600 2575);
FORCEPROP 2 LAST PATH I309
J 0
(-6975 2700);
DISPLAY 1.021277 (-6975 2700);
DISPLAY INVISIBLE (-6975 2700);
FORCEADD OFFPAGE..2
R 2
(-6700 2550);
FORCEPROP 2 LAST $XR0 100 
J 0
(-6985 2550);
DISPLAY 0.638298 (-6985 2550);
PAINT MONO (-6985 2550);
FORCEPROP 2 LAST CDS_LIB standard
J 0
(-6700 2550);
DISPLAY INVISIBLE (-6700 2550);
FORCEPROP 1 LAST OFFPAGE TRUE
J 2
(-7025 2425);
DISPLAY 0.872340 (-7025 2425);
PAINT GREEN (-7025 2425);
DISPLAY INVISIBLE (-7025 2425);
FORCEPROP 1 LAST COMMENT_BODY TRUE
J 2
(-6655 2455);
DISPLAY 0.872340 (-6655 2455);
PAINT GREEN (-6655 2455);
DISPLAY INVISIBLE (-6655 2455);
FORCEPROP 2 LAST PATH I310
J 0
(-6975 2600);
DISPLAY 1.021277 (-6975 2600);
DISPLAY INVISIBLE (-6975 2600);
FORCEADD OFFPAGE..2
R 2
(-6700 2500);
FORCEPROP 2 LAST $XR0 100 
J 0
(-6985 2500);
DISPLAY 0.638298 (-6985 2500);
PAINT MONO (-6985 2500);
FORCEPROP 2 LAST CDS_LIB standard
J 0
(-6700 2500);
DISPLAY INVISIBLE (-6700 2500);
FORCEPROP 1 LAST OFFPAGE TRUE
J 2
(-7025 2375);
DISPLAY 0.872340 (-7025 2375);
PAINT GREEN (-7025 2375);
DISPLAY INVISIBLE (-7025 2375);
FORCEPROP 1 LAST COMMENT_BODY TRUE
J 2
(-6655 2405);
DISPLAY 0.872340 (-6655 2405);
PAINT GREEN (-6655 2405);
DISPLAY INVISIBLE (-6655 2405);
FORCEPROP 2 LAST PATH I311
J 0
(-6975 2550);
DISPLAY 1.021277 (-6975 2550);
DISPLAY INVISIBLE (-6975 2550);
FORCEADD OFFPAGE..1
(-6700 2400);
FORCEPROP 2 LAST $XR0 100 
J 0
(-6952 2400);
DISPLAY 0.638298 (-6952 2400);
PAINT MONO (-6952 2400);
FORCEPROP 2 LAST CDS_LIB standard
J 0
(-6700 2400);
DISPLAY INVISIBLE (-6700 2400);
FORCEPROP 1 LAST OFFPAGE TRUE
J 0
(-6375 2275);
DISPLAY 0.872340 (-6375 2275);
PAINT GREEN (-6375 2275);
DISPLAY INVISIBLE (-6375 2275);
FORCEPROP 1 LAST COMMENT_BODY TRUE
J 0
(-6575 2300);
DISPLAY 0.872340 (-6575 2300);
PAINT GREEN (-6575 2300);
DISPLAY INVISIBLE (-6575 2300);
FORCEPROP 2 LAST PATH I312
J 0
(-6950 2450);
DISPLAY 1.021277 (-6950 2450);
DISPLAY INVISIBLE (-6950 2450);
FORCEADD Q_RES..1
(-6775 2200);
FORCEPROP 1 LAST LOCATION R502
J 0
(-7100 2200);
DISPLAY 0.489362 (-7100 2200);
PAINT SKYBLUE (-7100 2200);
FORCEPROP 0 LAST $SEC 1
J 0
(-6950 2250);
DISPLAY 0.680851 (-6950 2250);
PAINT MONO (-6950 2250);
DISPLAY INVISIBLE (-6950 2250);
FORCEPROP 0 LAST CDS_SEC 1
J 0
(-6950 2250);
DISPLAY 1.021277 (-6950 2250);
DISPLAY INVISIBLE (-6950 2250);
FORCEPROP 1 LASTPIN (-6875 2200) $PN 1
J 0
(-6863 2212);
DISPLAY 0.489362 (-6863 2212);
PAINT MONO (-6863 2212);
FORCEPROP 1 LASTPIN (-6675 2200) $PN 2
J 0
(-6713 2212);
DISPLAY 0.489362 (-6713 2212);
PAINT MONO (-6713 2212);
FORCEPROP 1 LAST PACK_TYPE 0402LF
J 0
(-7100 2175);
DISPLAY 0.489362 (-7100 2175);
PAINT SKYBLUE (-7100 2175);
FORCEPROP 1 LAST TOLERANCE 1%
J 0
(-6500 2200);
DISPLAY 0.489362 (-6500 2200);
PAINT SKYBLUE (-6500 2200);
FORCEPROP 1 LAST VALUE 15
J 2
(-6450 2200);
DISPLAY 0.489362 (-6450 2200);
PAINT SKYBLUE (-6450 2200);
FORCEPROP 1 LAST MATERIAL CHIP
J 0
(-6900 2325);
DISPLAY 0.638298 (-6900 2325);
PAINT SKYBLUE (-6900 2325);
DISPLAY INVISIBLE (-6900 2325);
FORCEPROP 1 LAST WATTAGE 1/16W
J 2
(-6550 2325);
DISPLAY 0.638298 (-6550 2325);
PAINT SKYBLUE (-6550 2325);
DISPLAY INVISIBLE (-6550 2325);
FORCEPROP 2 LAST CDS_LIB pure_quanta
J 0
(-6775 2200);
DISPLAY INVISIBLE (-6775 2200);
FORCEPROP 1 LAST PATH I313
J 0
(-6825 2350);
DISPLAY 0.978723 (-6825 2350);
PAINT WHITE (-6825 2350);
DISPLAY INVISIBLE (-6825 2350);
FORCEPROP 1 LAST PART_NUMBER CS01502FB03
J 0
(-6650 2175);
DISPLAY 0.489362 (-6650 2175);
PAINT SKYBLUE (-6650 2175);
DISPLAY INVISIBLE (-6650 2175);
FORCEADD OFFPAGE..5
(-6700 2300);
FORCEPROP 2 LAST $XR0 100 
J 0
(-6985 2300);
DISPLAY 0.638298 (-6985 2300);
PAINT MONO (-6985 2300);
FORCEPROP 2 LAST CDS_LIB standard
J 0
(-6700 2300);
DISPLAY INVISIBLE (-6700 2300);
FORCEPROP 1 LAST OFFPAGE TRUE
J 0
(-6375 2175);
DISPLAY 0.872340 (-6375 2175);
PAINT GREEN (-6375 2175);
DISPLAY INVISIBLE (-6375 2175);
FORCEPROP 1 LAST COMMENT_BODY TRUE
J 0
(-6600 2225);
DISPLAY 0.872340 (-6600 2225);
PAINT GREEN (-6600 2225);
DISPLAY INVISIBLE (-6600 2225);
FORCEPROP 2 LAST PATH I314
J 0
(-6975 2350);
DISPLAY 1.021277 (-6975 2350);
DISPLAY INVISIBLE (-6975 2350);
FORCEADD OFFPAGE..5
(-6700 2100);
FORCEPROP 2 LAST $XR0 100 
J 0
(-6985 2100);
DISPLAY 0.638298 (-6985 2100);
PAINT MONO (-6985 2100);
FORCEPROP 2 LAST CDS_LIB standard
J 0
(-6700 2100);
DISPLAY INVISIBLE (-6700 2100);
FORCEPROP 1 LAST OFFPAGE TRUE
J 0
(-6375 1975);
DISPLAY 0.872340 (-6375 1975);
PAINT GREEN (-6375 1975);
DISPLAY INVISIBLE (-6375 1975);
FORCEPROP 1 LAST COMMENT_BODY TRUE
J 0
(-6600 2025);
DISPLAY 0.872340 (-6600 2025);
PAINT GREEN (-6600 2025);
DISPLAY INVISIBLE (-6600 2025);
FORCEPROP 2 LAST PATH I315
J 0
(-6975 2150);
DISPLAY 1.021277 (-6975 2150);
DISPLAY INVISIBLE (-6975 2150);
FORCEADD OFFPAGE..1
(-7650 2200);
FORCEPROP 2 LAST $XR0 100 
J 0
(-7902 2200);
DISPLAY 0.638298 (-7902 2200);
PAINT MONO (-7902 2200);
FORCEPROP 2 LAST CDS_LIB mstr_standard
J 0
(-7650 2200);
DISPLAY INVISIBLE (-7650 2200);
FORCEPROP 1 LAST OFFPAGE TRUE
J 0
(-7325 2075);
DISPLAY 0.872340 (-7325 2075);
PAINT GREEN (-7325 2075);
DISPLAY INVISIBLE (-7325 2075);
FORCEPROP 1 LAST COMMENT_BODY TRUE
J 0
(-7525 2100);
DISPLAY 0.872340 (-7525 2100);
PAINT GREEN (-7525 2100);
DISPLAY INVISIBLE (-7525 2100);
FORCEPROP 2 LAST PATH I316
J 0
(-7900 2250);
DISPLAY 1.021277 (-7900 2250);
DISPLAY INVISIBLE (-7900 2250);
FORCEADD CAD_NOTE..1
(-7800 2475);
FORCEPROP 0 LAST L1 R1960 PLACE CLOSE TO CPU < 25MM
J 0
(-7950 2350);
DISPLAY 0.617021 (-7950 2350);
PAINT WHITE (-7950 2350);
FORCEPROP 2 LAST CDS_LIB pure_quanta_power
J 0
(-7800 2475);
DISPLAY INVISIBLE (-7800 2475);
FORCEPROP 1 LAST COMMENT_BODY TRUE
J 0
(-7775 2575);
DISPLAY 0.574468 (-7775 2575);
PAINT WHITE (-7775 2575);
DISPLAY INVISIBLE (-7775 2575);
FORCEADD QUANTA_TITLE_BLOCK_C..1
(-100 100);
FORCEPROP 0 LAST CDS_CON_LAST_MODIFIED Thu Sep 14 16:11:56 2023
J 0
(-1985 115);
DISPLAY INVISIBLE (-1985 115);
FORCEPROP 1 LAST CUSTOM_TXT_CDS <CON_LAST_MODIFIED>
J 0
(-1985 115);
DISPLAY 0.978723 (-1985 115);
FORCEPROP 2 LAST CUSTOM_TXT_CDS <XR_PAGE_TITLE>
J 0
(-7990 5350);
DISPLAY 0.638298 (-7990 5350);
PAINT PINK (-7990 5350);
DISPLAY INVISIBLE (-7990 5350);
FORCEPROP 1 LAST CUSTOM_TXT_CDS <NAME_2>
J 0
(-3275 150);
FORCEPROP 1 LAST CUSTOM_TXT_CDS <NAME_1>
J 0
(-3275 275);
FORCEPROP 1 LAST CUSTOM_TXT_CDS <Q_NUMBER>
J 0
(-1503 203);
DISPLAY 1.212766 (-1503 203);
FORCEPROP 1 LAST CUSTOM_TXT_CDS <Q_PROJ>
J 0
(-2482 202);
DISPLAY 1.212766 (-2482 202);
FORCEPROP 1 LAST CUSTOM_TXT_CDS <Q_REV>
J 0
(-284 203);
DISPLAY 1.212766 (-284 203);
FORCEPROP 1 LAST CUSTOM_TXT_CDS <CON_PAGE_NUM> OF <CON_TOTAL_PAGES>
J 0
(-546 118);
DISPLAY 0.978723 (-546 118);
FORCEPROP 1 LAST Q_TITLE CPU1 DDR CHC
J 0
(-9375 175);
DISPLAY 2.446809 (-9375 175);
PAINT GREEN (-9375 175);
FORCEPROP 2 LAST CDS_LIB pure_quanta
J 0
(-100 100);
DISPLAY INVISIBLE (-100 100);
FORCEPROP 1 LAST CDS_LMAN_SYM_OUTLINE -9475,6775,100,-125
J 0
(-100 100);
DISPLAY 0.468085 (-100 100);
PAINT GREEN (-100 100);
DISPLAY INVISIBLE (-100 100);
FORCEPROP 2 LAST PAGE_BORDER TRUE
J 0
(-7990 5350);
DISPLAY 0.638298 (-7990 5350);
PAINT PINK (-7990 5350);
DISPLAY INVISIBLE (-7990 5350);
FORCEPROP 2 LAST CDS_XR_PAGE_TITLE CR-39 : @T6G_MB_LIB.T6G(SCH_1):PAGE39
J 0
(-7990 5350);
DISPLAY 0.638298 (-7990 5350);
PAINT PINK (-7990 5350);
DISPLAY INVISIBLE (-7990 5350);
FORCEPROP 1 LAST Q_DEPT BU9
J 1
(-3863 149);
DISPLAY 1.957447 (-3863 149);
PAINT GREEN (-3863 149);
DISPLAY INVISIBLE (-3863 149);
FORCEPROP 1 LAST COMMENT_BODY TRUE
J 0
(-88 87);
DISPLAY 0.978723 (-88 87);
PAINT GREEN (-88 87);
DISPLAY INVISIBLE (-88 87);
WIRE 17 -1 (-3425 5375)(-3425 5325);
WIRE 17 -1 (-3425 5425)(-3425 5375);
WIRE 17 -1 (-3425 5325)(-3425 5275);
WIRE 17 -1 (-3425 5175)(-3425 5275);
WIRE 17 -1 (-3425 5475)(-3425 5425);
WIRE 17 -1 (-3425 5525)(-3425 5475);
WIRE 17 -1 (-3425 5125)(-3425 5175);
WIRE 17 -1 (-3425 5075)(-3425 5125);
WIRE 17 -1 (-3425 5575)(-3425 5525);
WIRE 17 -1 (-3425 5625)(-3425 5575);
WIRE 17 -1 (-3425 5025)(-3425 5075);
WIRE 17 -1 (-3425 5025)(-3425 4975);
WIRE 17 -1 (-3425 5725)(-3425 5625);
WIRE 17 -1 (-3425 5775)(-3425 5725);
WIRE 17 -1 (-3425 4975)(-3425 4925);
WIRE 17 -1 (-3425 4925)(-3425 4875);
WIRE 17 -1 (-3425 5825)(-3425 5775);
WIRE 17 -1 (-3425 5875)(-3425 5825);
WIRE 17 -1 (-3425 4875)(-3425 4825);
WIRE 17 -1 (-3425 4825)(-3425 4725);
WIRE 17 -1 (-3425 5925)(-3425 5875);
WIRE 17 -1 (-3425 5975)(-3425 5925);
WIRE 17 -1 (-3425 4725)(-3425 4675);
WIRE 17 -1 (-3425 4675)(-3425 4625);
WIRE 17 -1 (-3425 6025)(-3425 5975);
WIRE 17 -1 (-3425 6075)(-3425 6025);
WIRE 17 -1 (-3425 4625)(-3425 4575);
WIRE 17 -1 (-3425 4525)(-3425 4575);
WIRE 17 -1 (-3425 6075)(-2800 6075);
FORCEPROP 2 LAST SIG_NAME M_C_CPU1_SA_DQ<31:0>
J 2
(-2860 6085);
DISPLAY 0.489362 (-2860 6085);
WIRE 17 -1 (-3425 4475)(-3425 4525);
WIRE 17 -1 (-3425 4425)(-3425 4475);
WIRE 17 -1 (-3425 4375)(-3425 4425);
WIRE 17 -1 (-3425 4275)(-2800 4275);
FORCEPROP 2 LAST SIG_NAME M_C_CPU1_SB_DQ<31:0>
J 2
(-2860 4285);
DISPLAY 0.489362 (-2860 4285);
WIRE 17 -1 (-3425 4275)(-3425 4225);
WIRE 17 -1 (-3425 4225)(-3425 4175);
WIRE 17 -1 (-3425 4175)(-3425 4125);
WIRE 17 -1 (-3425 4125)(-3425 4075);
WIRE 17 -1 (-3425 4075)(-3425 4025);
WIRE 17 -1 (-3425 3925)(-3425 3825);
WIRE 17 -1 (-3425 3975)(-3425 3925);
WIRE 17 -1 (-3425 3825)(-3425 3775);
WIRE 17 -1 (-3425 3775)(-3425 3725);
WIRE 17 -1 (-3425 4025)(-3425 3975);
WIRE 17 -1 (-3425 3725)(-3425 3675);
WIRE 17 -1 (-3425 3675)(-3425 3625);
WIRE 17 -1 (-3425 3625)(-3425 3575);
WIRE 17 -1 (-3425 3575)(-3425 3525);
WIRE 17 -1 (-3425 3525)(-3425 3475);
WIRE 17 -1 (-3425 3375)(-3425 3475);
WIRE 17 -1 (-3425 3225)(-3425 3175);
WIRE 17 -1 (-3425 3225)(-3425 3275);
WIRE 17 -1 (-3425 3175)(-3425 3125);
WIRE 17 -1 (-3425 3125)(-3425 3075);
WIRE 17 -1 (-3425 3275)(-3425 3325);
WIRE 17 -1 (-3425 3325)(-3425 3375);
WIRE 17 -1 (-3425 3075)(-3425 3025);
WIRE 17 -1 (-3425 3025)(-3425 2925);
WIRE 17 -1 (-3425 2925)(-3425 2875);
WIRE 17 -1 (-3425 2875)(-3425 2825);
WIRE 17 -1 (-3425 2825)(-3425 2775);
WIRE 17 -1 (-3425 2725)(-3425 2775);
WIRE 17 -1 (-3425 2675)(-3425 2725);
WIRE 17 -1 (-3425 2625)(-3425 2675);
WIRE 17 -1 (-3425 2575)(-3425 2625);
WIRE 17 -1 (-3425 2225)(-3425 2275);
WIRE 17 -1 (-3425 2175)(-3425 2225);
WIRE 17 -1 (-3425 2275)(-3425 2325);
WIRE 17 -1 (-3425 2375)(-3425 2325);
WIRE 17 -1 (-3425 2125)(-3425 2175);
WIRE 17 -1 (-3425 2375)(-3425 2425);
WIRE 17 -1 (-3425 2475)(-3425 2425);
WIRE 17 -1 (-3425 2475)(-3425 2500);
WIRE 17 -1 (-3425 2500)(-2925 2500);
FORCEPROP 2 LAST SIG_NAME M_C_CPU1_SA_CB<7:0>
J 2
(-2925 2510);
DISPLAY 0.489362 (-2925 2510);
WIRE 17 -1 (-3425 2025)(-3425 2050);
WIRE 17 -1 (-3425 2025)(-3425 1975);
WIRE 17 -1 (-3425 2050)(-2925 2050);
FORCEPROP 2 LAST SIG_NAME M_C_CPU1_SB_CB<7:0>
J 2
(-2925 2060);
DISPLAY 0.489362 (-2925 2060);
WIRE 17 -1 (-3425 1925)(-3425 1975);
WIRE 17 -1 (-3425 1925)(-3425 1875);
WIRE 17 -1 (-3425 1825)(-3425 1875);
WIRE 17 -1 (-3425 1775)(-3425 1825);
WIRE 17 -1 (-3425 1725)(-3425 1775);
WIRE 17 -1 (-3425 1675)(-3425 1725);
WIRE 17 -1 (-6150 6025)(-6150 5925);
FORCEPROP 2 LAST SIG_NAME M_C_CPU1_SA_DQS_DN<9:0>
J 2
(-6185 6035);
DISPLAY 0.489362 (-6185 6035);
WIRE 17 -1 (-6150 5925)(-6150 5825);
WIRE 17 -1 (-6150 5825)(-6150 5725);
WIRE 17 -1 (-6150 5725)(-6150 5625);
WIRE 17 -1 (-6150 5525)(-6150 5625);
WIRE 17 -1 (-6150 5425)(-6150 5525);
WIRE 17 -1 (-5950 6075)(-5950 5975);
WIRE 17 -1 (-5950 6075)(-6750 6075);
FORCEPROP 2 LAST SIG_NAME M_C_CPU1_SA_DQS_DP<9:0>
J 2
(-6185 6085);
DISPLAY 0.489362 (-6185 6085);
WIRE 17 -1 (-6150 5325)(-6150 5425);
WIRE 17 -1 (-6150 5325)(-6150 5225);
WIRE 17 -1 (-6150 5225)(-6150 5125);
WIRE 17 -1 (-5950 5975)(-5950 5875);
WIRE 17 -1 (-5950 5875)(-5950 5775);
WIRE 17 -1 (-5950 5775)(-5950 5675);
WIRE 17 -1 (-5950 5575)(-5950 5675);
WIRE 17 -1 (-5950 5475)(-5950 5575);
WIRE 17 -1 (-5950 5375)(-5950 5475);
WIRE 17 -1 (-5950 5375)(-5950 5275);
WIRE 17 -1 (-5950 5275)(-5950 5175);
WIRE 17 -1 (-5950 4325)(-5950 4225);
WIRE 17 -1 (-5950 4325)(-5950 4425);
WIRE 17 -1 (-5950 4225)(-5950 4125);
WIRE 17 -1 (-5950 4425)(-5950 4525);
WIRE 17 -1 (-5950 4525)(-5950 4625);
WIRE 17 -1 (-5950 4725)(-5950 4625);
WIRE 17 -1 (-5950 4825)(-5950 4725);
WIRE 17 -1 (-5950 4925)(-5950 4825);
WIRE 17 -1 (-5950 5025)(-5950 4925);
WIRE 17 -1 (-5950 5025)(-6750 5025);
FORCEPROP 2 LAST SIG_NAME M_C_CPU1_SB_DQS_DP<9:0>
J 2
(-6185 5035);
DISPLAY 0.489362 (-6185 5035);
WIRE 17 -1 (-6150 4975)(-6150 4875);
FORCEPROP 2 LAST SIG_NAME M_C_CPU1_SB_DQS_DN<9:0>
J 2
(-6185 4985);
DISPLAY 0.489362 (-6185 4985);
WIRE 17 -1 (-6150 4875)(-6150 4775);
WIRE 17 -1 (-6150 4775)(-6150 4675);
WIRE 17 -1 (-6150 4675)(-6150 4575);
WIRE 17 -1 (-6150 4475)(-6150 4575);
WIRE 17 -1 (-6150 4375)(-6150 4475);
WIRE 17 -1 (-6150 4275)(-6150 4375);
WIRE 17 -1 (-6150 4275)(-6150 4175);
WIRE 17 -1 (-6150 4175)(-6150 4075);
WIRE 17 -1 (-6150 3875)(-6150 3925);
WIRE 17 -1 (-6150 3825)(-6150 3875);
WIRE 17 -1 (-6150 3925)(-6650 3925);
FORCEPROP 2 LAST SIG_NAME M_C_CPU1_SA_CA<6:0>
J 0
(-6650 3935);
DISPLAY 0.489362 (-6650 3935);
WIRE 17 -1 (-6150 3475)(-6150 3525);
WIRE 17 -1 (-6150 3425)(-6150 3475);
WIRE 17 -1 (-6150 3525)(-6650 3525);
FORCEPROP 2 LAST SIG_NAME M_C_CPU1_SB_CA<6:0>
J 0
(-6650 3535);
DISPLAY 0.489362 (-6650 3535);
WIRE 17 -1 (-6150 3775)(-6150 3825);
WIRE 17 -1 (-6150 3375)(-6150 3425);
WIRE 17 -1 (-6150 3725)(-6150 3775);
WIRE 17 -1 (-6150 3675)(-6150 3725);
WIRE 17 -1 (-6150 3625)(-6150 3675);
WIRE 17 -1 (-6150 3325)(-6150 3375);
WIRE 17 -1 (-6150 3275)(-6150 3325);
WIRE 17 -1 (-6150 3225)(-6150 3275);
WIRE 17 -1 (-6150 6025)(-6750 6025);
WIRE 17 -1 (-6150 4975)(-6750 4975);
WIRE 16 -1 (-7600 2200)(-6875 2200);
FORCEPROP 2 LAST SIG_NAME M_C_CPU1_ALERT_N
J 0
(-7560 2210);
DISPLAY 0.489362 (-7560 2210);
WIRE 16 -1 (-6675 2200)(-5550 2200);
FORCEPROP 2 LAST SIG_NAME M_C_CPU1_ALERT_R_N
J 0
(-6385 2210);
DISPLAY 0.489362 (-6385 2210);
FORCEPROP 2 LASTPROP $XRERR UNIQUE?
J 0
(-6625 2210);
DISPLAY 0.638298 (-6625 2210);
PAINT MONO (-6625 2210);
DISPLAY INVISIBLE (-6625 2210);
WIRE 16 -1 (-6650 1250)(-5550 1250);
FORCEPROP 2 LAST SIG_NAME TP_M_C_CPU1_SA_TEST39C
J 0
(-6635 1260);
DISPLAY 0.489362 (-6635 1260);
FORCEPROP 2 LASTPROP $XRERR UNIQUE?
J 0
(-6890 1250);
DISPLAY 0.638298 (-6890 1250);
PAINT MONO (-6890 1250);
DISPLAY INVISIBLE (-6890 1250);
WIRE 16 -1 (-6650 3000)(-5550 3000);
FORCEPROP 2 LAST SIG_NAME M_C_CPU1_CLK_DN<0>
J 0
(-6650 3010);
DISPLAY 0.489362 (-6650 3010);
WIRE 16 -1 (-6650 3050)(-5550 3050);
FORCEPROP 2 LAST SIG_NAME M_C_CPU1_CLK_DP<0>
J 0
(-6650 3060);
DISPLAY 0.489362 (-6650 3060);
WIRE 16 -1 (-6650 2850)(-5550 2850);
FORCEPROP 2 LAST SIG_NAME M_C_CPU1_SA_CS_N<1>
J 0
(-6650 2860);
DISPLAY 0.489362 (-6650 2860);
WIRE 16 -1 (-6650 2900)(-5550 2900);
FORCEPROP 2 LAST SIG_NAME M_C_CPU1_SA_CS_N<0>
J 0
(-6650 2910);
DISPLAY 0.489362 (-6650 2910);
WIRE 16 -1 (-6650 2750)(-5550 2750);
FORCEPROP 2 LAST SIG_NAME M_C_CPU1_SA_RSP<0>
J 0
(-6650 2760);
DISPLAY 0.489362 (-6650 2760);
WIRE 16 -1 (-6650 2650)(-5550 2650);
FORCEPROP 2 LAST SIG_NAME M_C_CPU1_SA_PAR
J 0
(-6650 2660);
DISPLAY 0.489362 (-6650 2660);
WIRE 16 -1 (-6650 2550)(-5550 2550);
FORCEPROP 2 LAST SIG_NAME M_C_CPU1_SB_CS_N<0>
J 0
(-6650 2560);
DISPLAY 0.489362 (-6650 2560);
WIRE 16 -1 (-6650 2500)(-5550 2500);
FORCEPROP 2 LAST SIG_NAME M_C_CPU1_SB_CS_N<1>
J 0
(-6650 2510);
DISPLAY 0.489362 (-6650 2510);
WIRE 16 -1 (-6650 2400)(-5550 2400);
FORCEPROP 2 LAST SIG_NAME M_C_CPU1_SB_RSP<0>
J 0
(-6650 2410);
DISPLAY 0.489362 (-6650 2410);
WIRE 16 -1 (-6650 2300)(-5550 2300);
FORCEPROP 2 LAST SIG_NAME M_C_CPU1_SB_PAR
J 0
(-6650 2310);
DISPLAY 0.489362 (-6650 2310);
WIRE 16 -1 (-6650 2100)(-5550 2100);
FORCEPROP 2 LAST SIG_NAME M_C_CPU1_RESET_N
J 0
(-6650 2110);
DISPLAY 0.489362 (-6650 2110);
WIRE 16 -1 (-6050 3200)(-5550 3200);
WIRE 16 -1 (-6050 4050)(-5550 4050);
WIRE 16 -1 (-6050 3600)(-5550 3600);
WIRE 16 -1 (-6050 3250)(-5550 3250);
WIRE 16 -1 (-6050 3650)(-5550 3650);
WIRE 16 -1 (-6050 3300)(-5550 3300);
WIRE 16 -1 (-6050 3700)(-5550 3700);
WIRE 16 -1 (-6050 3350)(-5550 3350);
WIRE 16 -1 (-6050 3750)(-5550 3750);
WIRE 16 -1 (-6050 3400)(-5550 3400);
WIRE 16 -1 (-6050 3800)(-5550 3800);
WIRE 16 -1 (-6050 3450)(-5550 3450);
WIRE 16 -1 (-6050 3850)(-5550 3850);
WIRE 16 -1 (-6050 3500)(-5550 3500);
WIRE 16 -1 (-6050 3900)(-5550 3900);
WIRE 16 -1 (-5850 4100)(-5550 4100);
WIRE 16 -1 (-5850 4300)(-5550 4300);
WIRE 16 -1 (-5850 4400)(-5550 4400);
WIRE 16 -1 (-5850 4500)(-5550 4500);
WIRE 16 -1 (-5850 4600)(-5550 4600);
WIRE 16 -1 (-6050 4150)(-5550 4150);
WIRE 16 -1 (-5850 4700)(-5550 4700);
WIRE 16 -1 (-6050 4250)(-5550 4250);
WIRE 16 -1 (-5850 4800)(-5550 4800);
WIRE 16 -1 (-6050 4350)(-5550 4350);
WIRE 16 -1 (-5850 4900)(-5550 4900);
WIRE 16 -1 (-6050 4450)(-5550 4450);
WIRE 16 -1 (-5850 5000)(-5550 5000);
WIRE 16 -1 (-6050 4550)(-5550 4550);
WIRE 16 -1 (-6050 5100)(-5550 5100);
WIRE 16 -1 (-6050 4650)(-5550 4650);
WIRE 16 -1 (-6050 4750)(-5550 4750);
WIRE 16 -1 (-6050 4850)(-5550 4850);
WIRE 16 -1 (-6050 4950)(-5550 4950);
WIRE 16 -1 (-5850 4200)(-5550 4200);
WIRE 16 -1 (-6050 6000)(-5550 6000);
WIRE 16 -1 (-5850 5150)(-5550 5150);
WIRE 16 -1 (-5850 5250)(-5550 5250);
WIRE 16 -1 (-5850 5350)(-5550 5350);
WIRE 16 -1 (-5850 5450)(-5550 5450);
WIRE 16 -1 (-5850 5550)(-5550 5550);
WIRE 16 -1 (-5850 5650)(-5550 5650);
WIRE 16 -1 (-6050 5200)(-5550 5200);
WIRE 16 -1 (-5850 5750)(-5550 5750);
WIRE 16 -1 (-6050 5300)(-5550 5300);
WIRE 16 -1 (-5850 5850)(-5550 5850);
WIRE 16 -1 (-6050 5400)(-5550 5400);
WIRE 16 -1 (-5850 5950)(-5550 5950);
WIRE 16 -1 (-6050 5500)(-5550 5500);
WIRE 16 -1 (-5850 6050)(-5550 6050);
WIRE 16 -1 (-6050 5600)(-5550 5600);
WIRE 16 -1 (-6050 5700)(-5550 5700);
WIRE 16 -1 (-6050 5800)(-5550 5800);
WIRE 16 -1 (-6050 5900)(-5550 5900);
WIRE 16 -1 (-3950 1650)(-3525 1650);
WIRE 16 -1 (-3525 1700)(-3950 1700);
WIRE 16 -1 (-3950 1750)(-3525 1750);
WIRE 16 -1 (-3950 1800)(-3525 1800);
WIRE 16 -1 (-3525 1850)(-3950 1850);
WIRE 16 -1 (-3950 1900)(-3525 1900);
WIRE 16 -1 (-3950 1950)(-3525 1950);
WIRE 16 -1 (-3950 2000)(-3525 2000);
WIRE 16 -1 (-3950 2250)(-3525 2250);
WIRE 16 -1 (-3950 2300)(-3525 2300);
WIRE 16 -1 (-3950 2350)(-3525 2350);
WIRE 16 -1 (-3950 2400)(-3525 2400);
WIRE 16 -1 (-3950 2450)(-3525 2450);
WIRE 16 -1 (-3950 2650)(-3525 2650);
WIRE 16 -1 (-3950 2700)(-3525 2700);
WIRE 16 -1 (-3950 2750)(-3525 2750);
WIRE 16 -1 (-3950 2800)(-3525 2800);
WIRE 16 -1 (-3950 2850)(-3525 2850);
WIRE 16 -1 (-3950 2900)(-3525 2900);
WIRE 16 -1 (-3950 3000)(-3525 3000);
WIRE 16 -1 (-3950 3050)(-3525 3050);
WIRE 16 -1 (-3950 2100)(-3525 2100);
WIRE 16 -1 (-3950 2150)(-3525 2150);
WIRE 16 -1 (-3950 2550)(-3525 2550);
WIRE 16 -1 (-3950 2200)(-3525 2200);
WIRE 16 -1 (-3950 2600)(-3525 2600);
WIRE 16 -1 (-3950 3900)(-3525 3900);
WIRE 16 -1 (-3950 3950)(-3525 3950);
WIRE 16 -1 (-3950 4000)(-3525 4000);
WIRE 16 -1 (-3950 4050)(-3525 4050);
WIRE 16 -1 (-3950 3200)(-3525 3200);
WIRE 16 -1 (-3950 3250)(-3525 3250);
WIRE 16 -1 (-3950 3300)(-3525 3300);
WIRE 16 -1 (-3950 3350)(-3525 3350);
WIRE 16 -1 (-3950 3450)(-3525 3450);
WIRE 16 -1 (-3950 3500)(-3525 3500);
WIRE 16 -1 (-3950 3550)(-3525 3550);
WIRE 16 -1 (-3950 3600)(-3525 3600);
WIRE 16 -1 (-3950 3650)(-3525 3650);
WIRE 16 -1 (-3950 3700)(-3525 3700);
WIRE 16 -1 (-3950 3100)(-3525 3100);
WIRE 16 -1 (-3950 3750)(-3525 3750);
WIRE 16 -1 (-3950 3150)(-3525 3150);
WIRE 16 -1 (-3950 3800)(-3525 3800);
WIRE 16 -1 (-3950 4700)(-3525 4700);
WIRE 16 -1 (-3950 4800)(-3525 4800);
WIRE 16 -1 (-3950 4850)(-3525 4850);
WIRE 16 -1 (-3950 4900)(-3525 4900);
WIRE 16 -1 (-3950 4950)(-3525 4950);
WIRE 16 -1 (-3950 4350)(-3525 4350);
WIRE 16 -1 (-3950 4100)(-3525 4100);
WIRE 16 -1 (-3950 4400)(-3525 4400);
WIRE 16 -1 (-3950 4150)(-3525 4150);
WIRE 16 -1 (-3950 4200)(-3525 4200);
WIRE 16 -1 (-3950 4250)(-3525 4250);
WIRE 16 -1 (-3950 5000)(-3525 5000);
WIRE 16 -1 (-3950 5050)(-3525 5050);
WIRE 16 -1 (-3950 4450)(-3525 4450);
WIRE 16 -1 (-3950 5100)(-3525 5100);
WIRE 16 -1 (-3950 4500)(-3525 4500);
WIRE 16 -1 (-3950 4550)(-3525 4550);
WIRE 16 -1 (-3950 4600)(-3525 4600);
WIRE 16 -1 (-3950 4650)(-3525 4650);
WIRE 16 -1 (-3950 5600)(-3525 5600);
WIRE 16 -1 (-3950 5350)(-3525 5350);
WIRE 16 -1 (-3950 5700)(-3525 5700);
WIRE 16 -1 (-3950 5400)(-3525 5400);
WIRE 16 -1 (-3950 5750)(-3525 5750);
WIRE 16 -1 (-3950 5450)(-3525 5450);
WIRE 16 -1 (-3950 5800)(-3525 5800);
WIRE 16 -1 (-3950 5500)(-3525 5500);
WIRE 16 -1 (-3950 5850)(-3525 5850);
WIRE 16 -1 (-3950 5900)(-3525 5900);
WIRE 16 -1 (-3950 5950)(-3525 5950);
WIRE 16 -1 (-3950 6000)(-3525 6000);
WIRE 16 -1 (-3950 6050)(-3525 6050);
WIRE 16 -1 (-3950 5150)(-3525 5150);
WIRE 16 -1 (-3950 5250)(-3525 5250);
WIRE 16 -1 (-3950 5550)(-3525 5550);
WIRE 16 -1 (-3950 5300)(-3525 5300);
QUIT
